(kicad_sch (version 20230121) (generator eeschema)

  (paper "A3")

  (title_block
    (title "Scalenode CM4 Baseboard")
    (date "2024-03-26")
    (rev "1.1.3")
    (company "Antmicro")
    (comment 1 "www.antmicro.com")
  )

  (junction (at 214.63 128.27) (diameter 0) (color 0 0 0 0)
  )
  (junction (at 110.49 149.86) (diameter 0) (color 0 0 0 0)
  )
  (junction (at 228.6 176.53) (diameter 0) (color 0 0 0 0)
  )
  (junction (at 184.15 93.98) (diameter 0) (color 0 0 0 0)
  )
  (junction (at 105.41 180.34) (diameter 0) (color 0 0 0 0)
  )
  (junction (at 303.53 185.42) (diameter 0) (color 0 0 0 0)
  )
  (junction (at 142.24 208.28) (diameter 0) (color 0 0 0 0)
  )
  (junction (at 314.96 185.42) (diameter 0) (color 0 0 0 0)
  )
  (junction (at 228.6 200.66) (diameter 0) (color 0 0 0 0)
  )
  (junction (at 138.43 149.86) (diameter 0) (color 0 0 0 0)
  )
  (junction (at 93.98 238.76) (diameter 0) (color 0 0 0 0)
  )
  (junction (at 234.95 176.53) (diameter 0) (color 0 0 0 0)
  )
  (junction (at 118.11 149.86) (diameter 0) (color 0 0 0 0)
  )
  (junction (at 242.57 200.66) (diameter 0) (color 0 0 0 0)
  )
  (junction (at 254 200.66) (diameter 0) (color 0 0 0 0)
  )
  (junction (at 215.9 176.53) (diameter 0) (color 0 0 0 0)
  )
  (junction (at 228.6 73.66) (diameter 0) (color 0 0 0 0)
  )
  (junction (at 73.66 86.36) (diameter 0) (color 0 0 0 0)
  )
  (junction (at 138.43 173.99) (diameter 0) (color 0 0 0 0)
  )
  (junction (at 157.48 208.28) (diameter 0) (color 0 0 0 0)
  )
  (junction (at 321.31 185.42) (diameter 0) (color 0 0 0 0)
  )
  (junction (at 125.73 180.34) (diameter 0) (color 0 0 0 0)
  )
  (junction (at 83.82 218.44) (diameter 0) (color 0 0 0 0)
  )
  (junction (at 125.73 149.86) (diameter 0) (color 0 0 0 0)
  )
  (junction (at 85.09 238.76) (diameter 0) (color 0 0 0 0)
  )
  (junction (at 228.6 93.98) (diameter 0) (color 0 0 0 0)
  )
  (junction (at 170.18 73.66) (diameter 0) (color 0 0 0 0)
  )
  (junction (at 345.44 200.66) (diameter 0) (color 0 0 0 0)
  )
  (junction (at 308.61 185.42) (diameter 0) (color 0 0 0 0)
  )
  (junction (at 93.98 247.65) (diameter 0) (color 0 0 0 0)
  )
  (junction (at 321.31 200.66) (diameter 0) (color 0 0 0 0)
  )
  (junction (at 162.56 173.99) (diameter 0) (color 0 0 0 0)
  )
  (junction (at 173.99 123.19) (diameter 0) (color 0 0 0 0)
  )
  (junction (at 149.86 208.28) (diameter 0) (color 0 0 0 0)
  )
  (junction (at 345.44 185.42) (diameter 0) (color 0 0 0 0)
  )
  (junction (at 81.28 149.86) (diameter 0) (color 0 0 0 0)
  )
  (junction (at 266.7 176.53) (diameter 0) (color 0 0 0 0)
  )
  (junction (at 177.8 83.82) (diameter 0) (color 0 0 0 0)
  )
  (junction (at 196.85 128.27) (diameter 0) (color 0 0 0 0)
  )
  (junction (at 132.08 180.34) (diameter 0) (color 0 0 0 0)
  )
  (junction (at 170.18 123.19) (diameter 0) (color 0 0 0 0)
  )
  (junction (at 163.83 63.5) (diameter 0) (color 0 0 0 0)
  )
  (junction (at 328.93 185.42) (diameter 0) (color 0 0 0 0)
  )
  (junction (at 50.8 158.75) (diameter 0) (color 0 0 0 0)
  )
  (junction (at 215.9 200.66) (diameter 0) (color 0 0 0 0)
  )
  (junction (at 234.95 200.66) (diameter 0) (color 0 0 0 0)
  )
  (junction (at 92.71 218.44) (diameter 0) (color 0 0 0 0)
  )
  (junction (at 222.25 176.53) (diameter 0) (color 0 0 0 0)
  )
  (junction (at 328.93 200.66) (diameter 0) (color 0 0 0 0)
  )
  (junction (at 110.49 180.34) (diameter 0) (color 0 0 0 0)
  )
  (junction (at 118.11 180.34) (diameter 0) (color 0 0 0 0)
  )
  (junction (at 254 176.53) (diameter 0) (color 0 0 0 0)
  )
  (junction (at 314.96 200.66) (diameter 0) (color 0 0 0 0)
  )
  (junction (at 222.25 200.66) (diameter 0) (color 0 0 0 0)
  )
  (junction (at 132.08 149.86) (diameter 0) (color 0 0 0 0)
  )
  (junction (at 93.98 243.84) (diameter 0) (color 0 0 0 0)
  )
  (junction (at 228.6 83.82) (diameter 0) (color 0 0 0 0)
  )
  (junction (at 308.61 200.66) (diameter 0) (color 0 0 0 0)
  )
  (junction (at 242.57 176.53) (diameter 0) (color 0 0 0 0)
  )
  (junction (at 177.8 123.19) (diameter 0) (color 0 0 0 0)
  )
  (junction (at 138.43 242.57) (diameter 0) (color 0 0 0 0)
  )
  (junction (at 96.52 238.76) (diameter 0) (color 0 0 0 0)
  )

  (no_connect (at 299.72 226.06))
  (no_connect (at 299.72 193.04))
  (no_connect (at 158.75 162.56))

  (wire (pts (xy 105.41 226.06) (xy 85.09 226.06))
    (stroke (width 0) (type default))
  )
  (wire (pts (xy 254 191.77) (xy 254 200.66))
    (stroke (width 0) (type default))
  )
  (wire (pts (xy 118.11 180.34) (xy 125.73 180.34))
    (stroke (width 0) (type default))
  )
  (wire (pts (xy 92.71 218.44) (xy 105.41 218.44))
    (stroke (width 0) (type default))
  )
  (wire (pts (xy 210.82 63.5) (xy 218.44 63.5))
    (stroke (width 0) (type default))
  )
  (wire (pts (xy 81.28 149.86) (xy 81.28 166.37))
    (stroke (width 0) (type default))
  )
  (wire (pts (xy 299.72 200.66) (xy 308.61 200.66))
    (stroke (width 0) (type default))
  )
  (wire (pts (xy 135.89 220.98) (xy 149.86 220.98))
    (stroke (width 0) (type default))
  )
  (wire (pts (xy 50.8 166.37) (xy 53.34 166.37))
    (stroke (width 0) (type default))
  )
  (wire (pts (xy 254 200.66) (xy 279.4 200.66))
    (stroke (width 0) (type default))
  )
  (wire (pts (xy 105.41 177.8) (xy 105.41 180.34))
    (stroke (width 0) (type default))
  )
  (wire (pts (xy 170.18 119.38) (xy 170.18 123.19))
    (stroke (width 0) (type default))
  )
  (wire (pts (xy 38.1 74.93) (xy 53.34 74.93))
    (stroke (width 0) (type default))
  )
  (wire (pts (xy 186.69 93.98) (xy 184.15 93.98))
    (stroke (width 0) (type default))
  )
  (wire (pts (xy 208.28 204.47) (xy 208.28 200.66))
    (stroke (width 0) (type default))
  )
  (wire (pts (xy 345.44 185.42) (xy 345.44 184.15))
    (stroke (width 0) (type default))
  )
  (wire (pts (xy 53.34 154.94) (xy 40.64 154.94))
    (stroke (width 0) (type default))
  )
  (wire (pts (xy 148.59 68.58) (xy 186.69 68.58))
    (stroke (width 0) (type default))
  )
  (wire (pts (xy 177.8 123.19) (xy 184.15 123.19))
    (stroke (width 0) (type default))
  )
  (wire (pts (xy 135.89 242.57) (xy 138.43 242.57))
    (stroke (width 0) (type default))
  )
  (wire (pts (xy 38.1 72.39) (xy 53.34 72.39))
    (stroke (width 0) (type default))
  )
  (wire (pts (xy 345.44 200.66) (xy 345.44 204.47))
    (stroke (width 0) (type default))
  )
  (wire (pts (xy 93.98 180.34) (xy 105.41 180.34))
    (stroke (width 0) (type default))
  )
  (wire (pts (xy 299.72 233.68) (xy 312.42 233.68))
    (stroke (width 0) (type default))
  )
  (wire (pts (xy 138.43 242.57) (xy 138.43 252.73))
    (stroke (width 0) (type default))
  )
  (wire (pts (xy 74.93 67.31) (xy 72.39 67.31))
    (stroke (width 0) (type default))
  )
  (wire (pts (xy 50.8 149.86) (xy 50.8 158.75))
    (stroke (width 0) (type default))
  )
  (wire (pts (xy 138.43 149.86) (xy 175.26 149.86))
    (stroke (width 0) (type default))
  )
  (wire (pts (xy 72.39 86.36) (xy 73.66 86.36))
    (stroke (width 0) (type default))
  )
  (wire (pts (xy 157.48 208.28) (xy 179.07 208.28))
    (stroke (width 0) (type default))
  )
  (wire (pts (xy 170.18 107.95) (xy 170.18 114.3))
    (stroke (width 0) (type default))
  )
  (wire (pts (xy 210.82 73.66) (xy 218.44 73.66))
    (stroke (width 0) (type default))
  )
  (wire (pts (xy 266.7 175.26) (xy 266.7 176.53))
    (stroke (width 0) (type default))
  )
  (wire (pts (xy 328.93 185.42) (xy 328.93 189.23))
    (stroke (width 0) (type default))
  )
  (wire (pts (xy 149.86 215.9) (xy 149.86 220.98))
    (stroke (width 0) (type default))
  )
  (wire (pts (xy 314.96 185.42) (xy 321.31 185.42))
    (stroke (width 0) (type default))
  )
  (wire (pts (xy 85.09 226.06) (xy 85.09 229.87))
    (stroke (width 0) (type default))
  )
  (wire (pts (xy 196.85 128.27) (xy 203.2 128.27))
    (stroke (width 0) (type default))
  )
  (wire (pts (xy 308.61 67.31) (xy 312.42 67.31))
    (stroke (width 0) (type default))
  )
  (wire (pts (xy 118.11 162.56) (xy 118.11 180.34))
    (stroke (width 0) (type default))
  )
  (wire (pts (xy 93.98 243.84) (xy 97.79 243.84))
    (stroke (width 0) (type default))
  )
  (wire (pts (xy 173.99 123.19) (xy 170.18 123.19))
    (stroke (width 0) (type default))
  )
  (wire (pts (xy 92.71 218.44) (xy 92.71 220.98))
    (stroke (width 0) (type default))
  )
  (wire (pts (xy 158.75 165.1) (xy 175.26 165.1))
    (stroke (width 0) (type default))
  )
  (wire (pts (xy 53.34 149.86) (xy 50.8 149.86))
    (stroke (width 0) (type default))
  )
  (wire (pts (xy 158.75 173.99) (xy 162.56 173.99))
    (stroke (width 0) (type default))
  )
  (wire (pts (xy 184.15 93.98) (xy 184.15 55.88))
    (stroke (width 0) (type default))
  )
  (wire (pts (xy 71.12 166.37) (xy 81.28 166.37))
    (stroke (width 0) (type default))
  )
  (wire (pts (xy 125.73 168.91) (xy 125.73 180.34))
    (stroke (width 0) (type default))
  )
  (wire (pts (xy 93.98 243.84) (xy 93.98 238.76))
    (stroke (width 0) (type default))
  )
  (wire (pts (xy 92.71 220.98) (xy 96.52 220.98))
    (stroke (width 0) (type default))
  )
  (wire (pts (xy 234.95 176.53) (xy 242.57 176.53))
    (stroke (width 0) (type default))
  )
  (wire (pts (xy 135.89 218.44) (xy 142.24 218.44))
    (stroke (width 0) (type default))
  )
  (wire (pts (xy 149.86 208.28) (xy 157.48 208.28))
    (stroke (width 0) (type default))
  )
  (wire (pts (xy 210.82 88.9) (xy 243.84 88.9))
    (stroke (width 0) (type default))
  )
  (wire (pts (xy 242.57 185.42) (xy 242.57 187.96))
    (stroke (width 0) (type default))
  )
  (wire (pts (xy 38.1 80.01) (xy 53.34 80.01))
    (stroke (width 0) (type default))
  )
  (wire (pts (xy 148.59 88.9) (xy 186.69 88.9))
    (stroke (width 0) (type default))
  )
  (wire (pts (xy 163.83 63.5) (xy 163.83 102.87))
    (stroke (width 0) (type default))
  )
  (wire (pts (xy 214.63 128.27) (xy 214.63 133.35))
    (stroke (width 0) (type default))
  )
  (wire (pts (xy 170.18 73.66) (xy 186.69 73.66))
    (stroke (width 0) (type default))
  )
  (wire (pts (xy 83.82 218.44) (xy 83.82 208.28))
    (stroke (width 0) (type default))
  )
  (wire (pts (xy 308.61 200.66) (xy 314.96 200.66))
    (stroke (width 0) (type default))
  )
  (wire (pts (xy 321.31 185.42) (xy 321.31 191.77))
    (stroke (width 0) (type default))
  )
  (wire (pts (xy 266.7 226.06) (xy 279.4 226.06))
    (stroke (width 0) (type default))
  )
  (wire (pts (xy 223.52 73.66) (xy 228.6 73.66))
    (stroke (width 0) (type default))
  )
  (wire (pts (xy 223.52 63.5) (xy 228.6 63.5))
    (stroke (width 0) (type default))
  )
  (wire (pts (xy 303.53 185.42) (xy 308.61 185.42))
    (stroke (width 0) (type default))
  )
  (wire (pts (xy 228.6 73.66) (xy 228.6 83.82))
    (stroke (width 0) (type default))
  )
  (wire (pts (xy 102.87 247.65) (xy 105.41 247.65))
    (stroke (width 0) (type default))
  )
  (wire (pts (xy 312.42 67.31) (xy 312.42 71.12))
    (stroke (width 0) (type default))
  )
  (wire (pts (xy 138.43 173.99) (xy 138.43 180.34))
    (stroke (width 0) (type default))
  )
  (wire (pts (xy 93.98 247.65) (xy 97.79 247.65))
    (stroke (width 0) (type default))
  )
  (wire (pts (xy 208.28 128.27) (xy 214.63 128.27))
    (stroke (width 0) (type default))
  )
  (wire (pts (xy 242.57 176.53) (xy 254 176.53))
    (stroke (width 0) (type default))
  )
  (wire (pts (xy 242.57 176.53) (xy 242.57 180.34))
    (stroke (width 0) (type default))
  )
  (wire (pts (xy 162.56 160.02) (xy 162.56 173.99))
    (stroke (width 0) (type default))
  )
  (wire (pts (xy 53.34 95.25) (xy 50.8 95.25))
    (stroke (width 0) (type default))
  )
  (wire (pts (xy 88.9 180.34) (xy 77.47 180.34))
    (stroke (width 0) (type default))
  )
  (wire (pts (xy 210.82 78.74) (xy 243.84 78.74))
    (stroke (width 0) (type default))
  )
  (wire (pts (xy 53.34 67.31) (xy 50.8 67.31))
    (stroke (width 0) (type default))
  )
  (wire (pts (xy 170.18 102.87) (xy 170.18 73.66))
    (stroke (width 0) (type default))
  )
  (wire (pts (xy 71.12 149.86) (xy 81.28 149.86))
    (stroke (width 0) (type default))
  )
  (wire (pts (xy 215.9 200.66) (xy 222.25 200.66))
    (stroke (width 0) (type default))
  )
  (wire (pts (xy 163.83 107.95) (xy 163.83 114.3))
    (stroke (width 0) (type default))
  )
  (wire (pts (xy 138.43 171.45) (xy 138.43 173.99))
    (stroke (width 0) (type default))
  )
  (wire (pts (xy 105.41 250.19) (xy 93.98 250.19))
    (stroke (width 0) (type default))
  )
  (wire (pts (xy 74.93 95.25) (xy 72.39 95.25))
    (stroke (width 0) (type default))
  )
  (wire (pts (xy 222.25 194.31) (xy 222.25 200.66))
    (stroke (width 0) (type default))
  )
  (wire (pts (xy 85.09 238.76) (xy 93.98 238.76))
    (stroke (width 0) (type default))
  )
  (wire (pts (xy 228.6 200.66) (xy 234.95 200.66))
    (stroke (width 0) (type default))
  )
  (wire (pts (xy 96.52 238.76) (xy 105.41 238.76))
    (stroke (width 0) (type default))
  )
  (wire (pts (xy 223.52 83.82) (xy 228.6 83.82))
    (stroke (width 0) (type default))
  )
  (wire (pts (xy 351.79 185.42) (xy 345.44 185.42))
    (stroke (width 0) (type default))
  )
  (wire (pts (xy 321.31 200.66) (xy 328.93 200.66))
    (stroke (width 0) (type default))
  )
  (wire (pts (xy 157.48 210.82) (xy 157.48 208.28))
    (stroke (width 0) (type default))
  )
  (wire (pts (xy 110.49 180.34) (xy 118.11 180.34))
    (stroke (width 0) (type default))
  )
  (wire (pts (xy 314.96 196.85) (xy 314.96 200.66))
    (stroke (width 0) (type default))
  )
  (wire (pts (xy 228.6 93.98) (xy 228.6 104.14))
    (stroke (width 0) (type default))
  )
  (wire (pts (xy 125.73 168.91) (xy 127 168.91))
    (stroke (width 0) (type default))
  )
  (wire (pts (xy 105.41 180.34) (xy 110.49 180.34))
    (stroke (width 0) (type default))
  )
  (wire (pts (xy 254 200.66) (xy 242.57 200.66))
    (stroke (width 0) (type default))
  )
  (wire (pts (xy 110.49 163.83) (xy 110.49 180.34))
    (stroke (width 0) (type default))
  )
  (wire (pts (xy 279.4 185.42) (xy 266.7 185.42))
    (stroke (width 0) (type default))
  )
  (wire (pts (xy 142.24 215.9) (xy 142.24 218.44))
    (stroke (width 0) (type default))
  )
  (wire (pts (xy 314.96 185.42) (xy 314.96 191.77))
    (stroke (width 0) (type default))
  )
  (wire (pts (xy 254 176.53) (xy 254 186.69))
    (stroke (width 0) (type default))
  )
  (wire (pts (xy 96.52 234.95) (xy 96.52 238.76))
    (stroke (width 0) (type default))
  )
  (wire (pts (xy 215.9 176.53) (xy 222.25 176.53))
    (stroke (width 0) (type default))
  )
  (wire (pts (xy 215.9 176.53) (xy 215.9 189.23))
    (stroke (width 0) (type default))
  )
  (wire (pts (xy 228.6 194.31) (xy 228.6 200.66))
    (stroke (width 0) (type default))
  )
  (wire (pts (xy 184.15 119.38) (xy 184.15 123.19))
    (stroke (width 0) (type default))
  )
  (wire (pts (xy 228.6 83.82) (xy 228.6 93.98))
    (stroke (width 0) (type default))
  )
  (wire (pts (xy 196.85 128.27) (xy 196.85 121.92))
    (stroke (width 0) (type default))
  )
  (wire (pts (xy 73.66 86.36) (xy 73.66 87.63))
    (stroke (width 0) (type default))
  )
  (wire (pts (xy 214.63 121.92) (xy 214.63 128.27))
    (stroke (width 0) (type default))
  )
  (wire (pts (xy 184.15 93.98) (xy 184.15 102.87))
    (stroke (width 0) (type default))
  )
  (wire (pts (xy 234.95 194.31) (xy 234.95 200.66))
    (stroke (width 0) (type default))
  )
  (wire (pts (xy 149.86 208.28) (xy 149.86 210.82))
    (stroke (width 0) (type default))
  )
  (wire (pts (xy 208.28 200.66) (xy 215.9 200.66))
    (stroke (width 0) (type default))
  )
  (wire (pts (xy 38.1 77.47) (xy 53.34 77.47))
    (stroke (width 0) (type default))
  )
  (wire (pts (xy 125.73 149.86) (xy 132.08 149.86))
    (stroke (width 0) (type default))
  )
  (wire (pts (xy 228.6 109.22) (xy 228.6 133.35))
    (stroke (width 0) (type default))
  )
  (wire (pts (xy 157.48 215.9) (xy 157.48 247.65))
    (stroke (width 0) (type default))
  )
  (wire (pts (xy 55.88 238.76) (xy 85.09 238.76))
    (stroke (width 0) (type default))
  )
  (wire (pts (xy 177.8 119.38) (xy 177.8 123.19))
    (stroke (width 0) (type default))
  )
  (wire (pts (xy 53.34 161.29) (xy 40.64 161.29))
    (stroke (width 0) (type default))
  )
  (wire (pts (xy 328.93 185.42) (xy 335.28 185.42))
    (stroke (width 0) (type default))
  )
  (wire (pts (xy 303.53 180.34) (xy 303.53 185.42))
    (stroke (width 0) (type default))
  )
  (wire (pts (xy 83.82 218.44) (xy 92.71 218.44))
    (stroke (width 0) (type default))
  )
  (wire (pts (xy 38.1 87.63) (xy 53.34 87.63))
    (stroke (width 0) (type default))
  )
  (wire (pts (xy 234.95 176.53) (xy 234.95 189.23))
    (stroke (width 0) (type default))
  )
  (wire (pts (xy 93.98 238.76) (xy 96.52 238.76))
    (stroke (width 0) (type default))
  )
  (wire (pts (xy 38.1 82.55) (xy 53.34 82.55))
    (stroke (width 0) (type default))
  )
  (wire (pts (xy 125.73 162.56) (xy 127 162.56))
    (stroke (width 0) (type default))
  )
  (wire (pts (xy 148.59 66.04) (xy 186.69 66.04))
    (stroke (width 0) (type default))
  )
  (wire (pts (xy 177.8 83.82) (xy 177.8 55.88))
    (stroke (width 0) (type default))
  )
  (wire (pts (xy 53.34 171.45) (xy 40.64 171.45))
    (stroke (width 0) (type default))
  )
  (wire (pts (xy 118.11 149.86) (xy 125.73 149.86))
    (stroke (width 0) (type default))
  )
  (wire (pts (xy 210.82 83.82) (xy 218.44 83.82))
    (stroke (width 0) (type default))
  )
  (wire (pts (xy 137.16 231.14) (xy 135.89 231.14))
    (stroke (width 0) (type default))
  )
  (wire (pts (xy 77.47 180.34) (xy 77.47 158.75))
    (stroke (width 0) (type default))
  )
  (wire (pts (xy 105.41 228.6) (xy 96.52 228.6))
    (stroke (width 0) (type default))
  )
  (wire (pts (xy 210.82 66.04) (xy 243.84 66.04))
    (stroke (width 0) (type default))
  )
  (wire (pts (xy 93.98 247.65) (xy 93.98 243.84))
    (stroke (width 0) (type default))
  )
  (wire (pts (xy 210.82 93.98) (xy 218.44 93.98))
    (stroke (width 0) (type default))
  )
  (wire (pts (xy 132.08 168.91) (xy 138.43 168.91))
    (stroke (width 0) (type default))
  )
  (wire (pts (xy 314.96 200.66) (xy 321.31 200.66))
    (stroke (width 0) (type default))
  )
  (wire (pts (xy 102.87 243.84) (xy 105.41 243.84))
    (stroke (width 0) (type default))
  )
  (wire (pts (xy 148.59 78.74) (xy 186.69 78.74))
    (stroke (width 0) (type default))
  )
  (wire (pts (xy 228.6 176.53) (xy 228.6 189.23))
    (stroke (width 0) (type default))
  )
  (wire (pts (xy 118.11 149.86) (xy 118.11 157.48))
    (stroke (width 0) (type default))
  )
  (wire (pts (xy 228.6 63.5) (xy 228.6 73.66))
    (stroke (width 0) (type default))
  )
  (wire (pts (xy 196.85 134.62) (xy 196.85 128.27))
    (stroke (width 0) (type default))
  )
  (wire (pts (xy 135.89 250.19) (xy 139.7 250.19))
    (stroke (width 0) (type default))
  )
  (wire (pts (xy 125.73 180.34) (xy 132.08 180.34))
    (stroke (width 0) (type default))
  )
  (wire (pts (xy 266.7 176.53) (xy 254 176.53))
    (stroke (width 0) (type default))
  )
  (wire (pts (xy 177.8 83.82) (xy 177.8 102.87))
    (stroke (width 0) (type default))
  )
  (wire (pts (xy 345.44 200.66) (xy 345.44 199.39))
    (stroke (width 0) (type default))
  )
  (wire (pts (xy 55.88 218.44) (xy 83.82 218.44))
    (stroke (width 0) (type default))
  )
  (wire (pts (xy 132.08 162.56) (xy 138.43 162.56))
    (stroke (width 0) (type default))
  )
  (wire (pts (xy 81.28 149.86) (xy 88.9 149.86))
    (stroke (width 0) (type default))
  )
  (wire (pts (xy 83.82 208.28) (xy 142.24 208.28))
    (stroke (width 0) (type default))
  )
  (wire (pts (xy 135.89 237.49) (xy 138.43 237.49))
    (stroke (width 0) (type default))
  )
  (wire (pts (xy 85.09 234.95) (xy 85.09 238.76))
    (stroke (width 0) (type default))
  )
  (wire (pts (xy 223.52 93.98) (xy 228.6 93.98))
    (stroke (width 0) (type default))
  )
  (wire (pts (xy 170.18 123.19) (xy 163.83 123.19))
    (stroke (width 0) (type default))
  )
  (wire (pts (xy 158.75 160.02) (xy 162.56 160.02))
    (stroke (width 0) (type default))
  )
  (wire (pts (xy 135.89 247.65) (xy 157.48 247.65))
    (stroke (width 0) (type default))
  )
  (wire (pts (xy 163.83 63.5) (xy 186.69 63.5))
    (stroke (width 0) (type default))
  )
  (wire (pts (xy 228.6 176.53) (xy 234.95 176.53))
    (stroke (width 0) (type default))
  )
  (wire (pts (xy 53.34 144.78) (xy 40.64 144.78))
    (stroke (width 0) (type default))
  )
  (wire (pts (xy 234.95 200.66) (xy 242.57 200.66))
    (stroke (width 0) (type default))
  )
  (wire (pts (xy 266.7 218.44) (xy 279.4 218.44))
    (stroke (width 0) (type default))
  )
  (wire (pts (xy 142.24 208.28) (xy 149.86 208.28))
    (stroke (width 0) (type default))
  )
  (wire (pts (xy 299.72 218.44) (xy 312.42 218.44))
    (stroke (width 0) (type default))
  )
  (wire (pts (xy 96.52 228.6) (xy 96.52 229.87))
    (stroke (width 0) (type default))
  )
  (wire (pts (xy 135.89 234.95) (xy 149.86 234.95))
    (stroke (width 0) (type default))
  )
  (wire (pts (xy 210.82 99.06) (xy 243.84 99.06))
    (stroke (width 0) (type default))
  )
  (wire (pts (xy 210.82 68.58) (xy 243.84 68.58))
    (stroke (width 0) (type default))
  )
  (wire (pts (xy 148.59 96.52) (xy 186.69 96.52))
    (stroke (width 0) (type default))
  )
  (wire (pts (xy 73.66 85.09) (xy 73.66 86.36))
    (stroke (width 0) (type default))
  )
  (wire (pts (xy 38.1 85.09) (xy 53.34 85.09))
    (stroke (width 0) (type default))
  )
  (wire (pts (xy 38.1 90.17) (xy 53.34 90.17))
    (stroke (width 0) (type default))
  )
  (wire (pts (xy 93.98 250.19) (xy 93.98 247.65))
    (stroke (width 0) (type default))
  )
  (wire (pts (xy 132.08 149.86) (xy 138.43 149.86))
    (stroke (width 0) (type default))
  )
  (wire (pts (xy 308.61 185.42) (xy 308.61 191.77))
    (stroke (width 0) (type default))
  )
  (wire (pts (xy 170.18 73.66) (xy 170.18 55.88))
    (stroke (width 0) (type default))
  )
  (wire (pts (xy 110.49 149.86) (xy 118.11 149.86))
    (stroke (width 0) (type default))
  )
  (wire (pts (xy 148.59 86.36) (xy 186.69 86.36))
    (stroke (width 0) (type default))
  )
  (wire (pts (xy 321.31 185.42) (xy 328.93 185.42))
    (stroke (width 0) (type default))
  )
  (wire (pts (xy 148.59 76.2) (xy 186.69 76.2))
    (stroke (width 0) (type default))
  )
  (wire (pts (xy 184.15 107.95) (xy 184.15 114.3))
    (stroke (width 0) (type default))
  )
  (wire (pts (xy 210.82 76.2) (xy 243.84 76.2))
    (stroke (width 0) (type default))
  )
  (wire (pts (xy 45.72 95.25) (xy 43.18 95.25))
    (stroke (width 0) (type default))
  )
  (wire (pts (xy 321.31 196.85) (xy 321.31 200.66))
    (stroke (width 0) (type default))
  )
  (wire (pts (xy 177.8 107.95) (xy 177.8 114.3))
    (stroke (width 0) (type default))
  )
  (wire (pts (xy 162.56 173.99) (xy 162.56 180.34))
    (stroke (width 0) (type default))
  )
  (wire (pts (xy 163.83 119.38) (xy 163.83 123.19))
    (stroke (width 0) (type default))
  )
  (wire (pts (xy 308.61 185.42) (xy 314.96 185.42))
    (stroke (width 0) (type default))
  )
  (wire (pts (xy 138.43 149.86) (xy 138.43 160.02))
    (stroke (width 0) (type default))
  )
  (wire (pts (xy 137.16 226.06) (xy 135.89 226.06))
    (stroke (width 0) (type default))
  )
  (wire (pts (xy 215.9 194.31) (xy 215.9 200.66))
    (stroke (width 0) (type default))
  )
  (wire (pts (xy 279.4 193.04) (xy 265.43 193.04))
    (stroke (width 0) (type default))
  )
  (wire (pts (xy 201.93 176.53) (xy 215.9 176.53))
    (stroke (width 0) (type default))
  )
  (wire (pts (xy 328.93 200.66) (xy 345.44 200.66))
    (stroke (width 0) (type default))
  )
  (wire (pts (xy 173.99 130.81) (xy 173.99 134.62))
    (stroke (width 0) (type default))
  )
  (wire (pts (xy 142.24 210.82) (xy 142.24 208.28))
    (stroke (width 0) (type default))
  )
  (wire (pts (xy 266.7 233.68) (xy 279.4 233.68))
    (stroke (width 0) (type default))
  )
  (wire (pts (xy 210.82 96.52) (xy 243.84 96.52))
    (stroke (width 0) (type default))
  )
  (wire (pts (xy 222.25 176.53) (xy 222.25 189.23))
    (stroke (width 0) (type default))
  )
  (wire (pts (xy 222.25 200.66) (xy 228.6 200.66))
    (stroke (width 0) (type default))
  )
  (wire (pts (xy 208.28 121.92) (xy 214.63 121.92))
    (stroke (width 0) (type default))
  )
  (wire (pts (xy 45.72 67.31) (xy 43.18 67.31))
    (stroke (width 0) (type default))
  )
  (wire (pts (xy 50.8 158.75) (xy 77.47 158.75))
    (stroke (width 0) (type default))
  )
  (wire (pts (xy 125.73 149.86) (xy 125.73 162.56))
    (stroke (width 0) (type default))
  )
  (wire (pts (xy 138.43 237.49) (xy 138.43 242.57))
    (stroke (width 0) (type default))
  )
  (wire (pts (xy 210.82 86.36) (xy 243.84 86.36))
    (stroke (width 0) (type default))
  )
  (wire (pts (xy 93.98 149.86) (xy 110.49 149.86))
    (stroke (width 0) (type default))
  )
  (wire (pts (xy 299.72 185.42) (xy 303.53 185.42))
    (stroke (width 0) (type default))
  )
  (wire (pts (xy 50.8 158.75) (xy 50.8 166.37))
    (stroke (width 0) (type default))
  )
  (wire (pts (xy 308.61 196.85) (xy 308.61 200.66))
    (stroke (width 0) (type default))
  )
  (wire (pts (xy 110.49 154.94) (xy 110.49 149.86))
    (stroke (width 0) (type default))
  )
  (wire (pts (xy 222.25 176.53) (xy 228.6 176.53))
    (stroke (width 0) (type default))
  )
  (wire (pts (xy 148.59 99.06) (xy 186.69 99.06))
    (stroke (width 0) (type default))
  )
  (wire (pts (xy 173.99 125.73) (xy 173.99 123.19))
    (stroke (width 0) (type default))
  )
  (wire (pts (xy 173.99 123.19) (xy 177.8 123.19))
    (stroke (width 0) (type default))
  )
  (wire (pts (xy 101.6 220.98) (xy 105.41 220.98))
    (stroke (width 0) (type default))
  )
  (wire (pts (xy 312.42 64.77) (xy 308.61 64.77))
    (stroke (width 0) (type default))
  )
  (wire (pts (xy 328.93 196.85) (xy 328.93 200.66))
    (stroke (width 0) (type default))
  )
  (wire (pts (xy 266.7 185.42) (xy 266.7 176.53))
    (stroke (width 0) (type default))
  )
  (wire (pts (xy 177.8 83.82) (xy 186.69 83.82))
    (stroke (width 0) (type default))
  )
  (wire (pts (xy 196.85 121.92) (xy 203.2 121.92))
    (stroke (width 0) (type default))
  )
  (wire (pts (xy 242.57 195.58) (xy 242.57 200.66))
    (stroke (width 0) (type default))
  )
  (wire (pts (xy 340.36 185.42) (xy 345.44 185.42))
    (stroke (width 0) (type default))
  )
  (wire (pts (xy 163.83 63.5) (xy 163.83 55.88))
    (stroke (width 0) (type default))
  )
  (wire (pts (xy 132.08 180.34) (xy 138.43 180.34))
    (stroke (width 0) (type default))
  )

  (text "Alt. PoE Controller" (at 95.25 202.692 0)
    (effects (font (size 2.54 2.54) (thickness 0.508) bold) (justify left bottom))
  )
  (text "Aux 5V0 power supply" (at 290.576 46.482 0)
    (effects (font (size 2.54 2.54) (thickness 0.508) bold) (justify left bottom))
  )
  (text "PoE Controller" (at 97.028 130.683 0)
    (effects (font (size 2.54 2.54) (thickness 0.508) bold) (justify left bottom))
  )
  (text "Ethernet connector" (at 44.958 50.927 0)
    (effects (font (size 2.54 2.54) bold) (justify left bottom))
  )
  (text "5V DC/DC converter" (at 261.112 160.528 0)
    (effects (font (size 2.54 2.54) bold) (justify left bottom))
  )
  (text "PoE transformer" (at 184.658 47.498 0)
    (effects (font (size 2.54 2.54) bold) (justify left bottom))
  )

  (label "PAIR45" (at 177.8 55.88 270) (fields_autoplaced)
    (effects (font (size 1.27 1.27)) (justify right bottom))
  )
  (label "VDD_POE_IN" (at 266.7 218.44 0) (fields_autoplaced)
    (effects (font (size 1.27 1.27)) (justify left bottom))
  )
  (label "T_ETH_D2_N" (at 38.1 82.55 0) (fields_autoplaced)
    (effects (font (size 1.27 1.27)) (justify left bottom))
  )
  (label "T_ETH_D1_P" (at 38.1 77.47 0) (fields_autoplaced)
    (effects (font (size 1.27 1.27)) (justify left bottom))
  )
  (label "VDD_POE_IN" (at 201.93 176.53 0) (fields_autoplaced)
    (effects (font (size 1.27 1.27)) (justify left bottom))
  )
  (label "T_ETH_D0_N" (at 148.59 68.58 0) (fields_autoplaced)
    (effects (font (size 1.27 1.27)) (justify left bottom))
  )
  (label "VDD_POE_IN" (at 55.88 218.44 0) (fields_autoplaced)
    (effects (font (size 1.27 1.27)) (justify left bottom))
  )
  (label "T_ETH_D1_N" (at 148.59 78.74 0) (fields_autoplaced)
    (effects (font (size 1.27 1.27)) (justify left bottom))
  )
  (label "POE_ACTIVE" (at 149.86 234.95 180) (fields_autoplaced)
    (effects (font (size 1.27 1.27)) (justify right bottom))
  )
  (label "POE_ACTIVE" (at 265.43 193.04 0) (fields_autoplaced)
    (effects (font (size 1.27 1.27)) (justify left bottom))
  )
  (label "VDD_POE_IN" (at 179.07 208.28 180) (fields_autoplaced)
    (effects (font (size 1.27 1.27)) (justify right bottom))
  )
  (label "T_ETH_D0_P" (at 38.1 72.39 0) (fields_autoplaced)
    (effects (font (size 1.27 1.27)) (justify left bottom))
  )
  (label "VO5V" (at 312.42 218.44 0) (fields_autoplaced)
    (effects (font (size 1.27 1.27)) (justify left bottom))
  )
  (label "T_ETH_D3_N" (at 148.59 99.06 0) (fields_autoplaced)
    (effects (font (size 1.27 1.27)) (justify left bottom))
  )
  (label "POE_ACTIVE" (at 266.7 226.06 0) (fields_autoplaced)
    (effects (font (size 1.27 1.27)) (justify left bottom))
  )
  (label "VDD_POE_IN" (at 175.26 149.86 180) (fields_autoplaced)
    (effects (font (size 1.27 1.27)) (justify right bottom))
  )
  (label "PAIR36" (at 40.64 154.94 0) (fields_autoplaced)
    (effects (font (size 1.27 1.27)) (justify left bottom))
  )
  (label "T_ETH_D1_P" (at 148.59 76.2 0) (fields_autoplaced)
    (effects (font (size 1.27 1.27)) (justify left bottom))
  )
  (label "VO5V" (at 303.53 180.34 0) (fields_autoplaced)
    (effects (font (size 1.27 1.27)) (justify left bottom))
  )
  (label "POE_ACTIVE" (at 175.26 165.1 180) (fields_autoplaced)
    (effects (font (size 1.27 1.27)) (justify right bottom))
  )
  (label "T_ETH_D3_P" (at 148.59 96.52 0) (fields_autoplaced)
    (effects (font (size 1.27 1.27)) (justify left bottom))
  )
  (label "PAIR45" (at 40.64 161.29 0) (fields_autoplaced)
    (effects (font (size 1.27 1.27)) (justify left bottom))
  )
  (label "PAIR36" (at 170.18 55.88 270) (fields_autoplaced)
    (effects (font (size 1.27 1.27)) (justify right bottom))
  )
  (label "T_ETH_D3_P" (at 38.1 87.63 0) (fields_autoplaced)
    (effects (font (size 1.27 1.27)) (justify left bottom))
  )
  (label "T_ETH_D0_P" (at 148.59 66.04 0) (fields_autoplaced)
    (effects (font (size 1.27 1.27)) (justify left bottom))
  )
  (label "VSS" (at 55.88 238.76 0) (fields_autoplaced)
    (effects (font (size 1.27 1.27)) (justify left bottom))
  )
  (label "PAIR12" (at 163.83 55.88 270) (fields_autoplaced)
    (effects (font (size 1.27 1.27)) (justify right bottom))
  )
  (label "T_ETH_D3_N" (at 38.1 90.17 0) (fields_autoplaced)
    (effects (font (size 1.27 1.27)) (justify left bottom))
  )
  (label "T_ETH_D0_N" (at 38.1 74.93 0) (fields_autoplaced)
    (effects (font (size 1.27 1.27)) (justify left bottom))
  )
  (label "T_ETH_D2_P" (at 148.59 86.36 0) (fields_autoplaced)
    (effects (font (size 1.27 1.27)) (justify left bottom))
  )
  (label "PAIR78" (at 40.64 171.45 0) (fields_autoplaced)
    (effects (font (size 1.27 1.27)) (justify left bottom))
  )
  (label "PAIR78" (at 184.15 55.88 270) (fields_autoplaced)
    (effects (font (size 1.27 1.27)) (justify right bottom))
  )
  (label "T_ETH_D2_P" (at 38.1 80.01 0) (fields_autoplaced)
    (effects (font (size 1.27 1.27)) (justify left bottom))
  )
  (label "T_ETH_D2_N" (at 148.59 88.9 0) (fields_autoplaced)
    (effects (font (size 1.27 1.27)) (justify left bottom))
  )
  (label "PAIR12" (at 40.64 144.78 0) (fields_autoplaced)
    (effects (font (size 1.27 1.27)) (justify left bottom))
  )
  (label "T_ETH_D1_N" (at 38.1 85.09 0) (fields_autoplaced)
    (effects (font (size 1.27 1.27)) (justify left bottom))
  )

  (global_label "ETH_LEDY" (shape input) (at 74.93 95.25 0) (fields_autoplaced)
    (effects (font (size 1.27 1.27)) (justify left))
    (property "Intersheetrefs" "${INTERSHEET_REFS}" (at 86.2047 95.1706 0)
      (effects (font (size 1.27 1.27)) (justify left) hide)
    )
  )
  (global_label "TRD3_N" (shape input) (at 243.84 99.06 0) (fields_autoplaced)
    (effects (font (size 1.27 1.27)) (justify left))
    (property "Intersheetrefs" "${INTERSHEET_REFS}" (at 253.1794 98.9806 0)
      (effects (font (size 1.27 1.27)) (justify left) hide)
    )
  )
  (global_label "VCC5V0" (shape input) (at 351.79 185.42 0) (fields_autoplaced)
    (effects (font (size 1.27 1.27)) (justify left))
    (property "Intersheetrefs" "${INTERSHEET_REFS}" (at 361.2504 185.3406 0)
      (effects (font (size 1.27 1.27)) (justify left) hide)
    )
  )
  (global_label "VCC5V0" (shape input) (at 312.42 64.77 0) (fields_autoplaced)
    (effects (font (size 1.27 1.27)) (justify left))
    (property "Intersheetrefs" "${INTERSHEET_REFS}" (at 321.8804 64.6906 0)
      (effects (font (size 1.27 1.27)) (justify left) hide)
    )
  )
  (global_label "TRD1_N" (shape input) (at 243.84 78.74 0) (fields_autoplaced)
    (effects (font (size 1.27 1.27)) (justify left))
    (property "Intersheetrefs" "${INTERSHEET_REFS}" (at 253.1794 78.6606 0)
      (effects (font (size 1.27 1.27)) (justify left) hide)
    )
  )
  (global_label "TRD2_P" (shape input) (at 243.84 86.36 0) (fields_autoplaced)
    (effects (font (size 1.27 1.27)) (justify left))
    (property "Intersheetrefs" "${INTERSHEET_REFS}" (at 253.119 86.2806 0)
      (effects (font (size 1.27 1.27)) (justify left) hide)
    )
  )
  (global_label "TRD0_N" (shape input) (at 243.84 68.58 0) (fields_autoplaced)
    (effects (font (size 1.27 1.27)) (justify left))
    (property "Intersheetrefs" "${INTERSHEET_REFS}" (at 253.1794 68.5006 0)
      (effects (font (size 1.27 1.27)) (justify left) hide)
    )
  )
  (global_label "TRD0_P" (shape input) (at 243.84 66.04 0) (fields_autoplaced)
    (effects (font (size 1.27 1.27)) (justify left))
    (property "Intersheetrefs" "${INTERSHEET_REFS}" (at 253.119 65.9606 0)
      (effects (font (size 1.27 1.27)) (justify left) hide)
    )
  )
  (global_label "TRD1_P" (shape input) (at 243.84 76.2 0) (fields_autoplaced)
    (effects (font (size 1.27 1.27)) (justify left))
    (property "Intersheetrefs" "${INTERSHEET_REFS}" (at 253.119 76.1206 0)
      (effects (font (size 1.27 1.27)) (justify left) hide)
    )
  )
  (global_label "ETH_LEDG" (shape input) (at 74.93 67.31 0) (fields_autoplaced)
    (effects (font (size 1.27 1.27)) (justify left))
    (property "Intersheetrefs" "${INTERSHEET_REFS}" (at 86.3861 67.2306 0)
      (effects (font (size 1.27 1.27)) (justify left) hide)
    )
  )
  (global_label "3V3_RPi" (shape input) (at 43.18 67.31 180) (fields_autoplaced)
    (effects (font (size 1.27 1.27)) (justify right))
    (property "Intersheetrefs" "${INTERSHEET_REFS}" (at 33.2358 67.2306 0)
      (effects (font (size 1.27 1.27)) (justify right) hide)
    )
  )
  (global_label "VSS" (shape input) (at 105.41 177.8 90) (fields_autoplaced)
    (effects (font (size 1.27 1.27)) (justify left))
    (property "Intersheetrefs" "${INTERSHEET_REFS}" (at 105.3306 171.9682 90)
      (effects (font (size 1.27 1.27)) (justify left) hide)
    )
  )
  (global_label "3V3_RPi" (shape input) (at 43.18 95.25 180) (fields_autoplaced)
    (effects (font (size 1.27 1.27)) (justify right))
    (property "Intersheetrefs" "${INTERSHEET_REFS}" (at 33.2358 95.1706 0)
      (effects (font (size 1.27 1.27)) (justify right) hide)
    )
  )
  (global_label "TRD2_N" (shape input) (at 243.84 88.9 0) (fields_autoplaced)
    (effects (font (size 1.27 1.27)) (justify left))
    (property "Intersheetrefs" "${INTERSHEET_REFS}" (at 253.1794 88.8206 0)
      (effects (font (size 1.27 1.27)) (justify left) hide)
    )
  )
  (global_label "TRD3_P" (shape input) (at 243.84 96.52 0) (fields_autoplaced)
    (effects (font (size 1.27 1.27)) (justify left))
    (property "Intersheetrefs" "${INTERSHEET_REFS}" (at 253.119 96.4406 0)
      (effects (font (size 1.27 1.27)) (justify left) hide)
    )
  )

  (symbol (lib_id "scalenode-cm4-baseboard:R_220R_0402") (at 50.8 95.25 0) (mirror y) (unit 1)
    (in_bom yes) (on_board yes) (dnp no)
    (property "Reference" "R21" (at 45.72 99.06 0)
      (effects (font (size 1.27 1.27) (thickness 0.15)) (justify right bottom))
    )
    (property "Value" "R_220R_0402" (at 30.48 107.95 0)
      (effects (font (size 1.27 1.27) (thickness 0.15)) (justify left bottom) hide)
    )
    (property "Footprint" "scalenode-cm4-baseboard-footprints:R_0402_1005Metric" (at 30.48 110.49 0)
      (effects (font (size 1.27 1.27) (thickness 0.15)) (justify left bottom) hide)
    )
    (property "Datasheet" "https://www.bourns.com/docs/product-datasheets/cr.pdf" (at 30.48 113.03 0)
      (effects (font (size 1.27 1.27) (thickness 0.15)) (justify left bottom) hide)
    )
    (property "Manufacturer" "Bourns" (at 30.48 118.11 0)
      (effects (font (size 1.27 1.27) (thickness 0.15)) (justify left bottom) hide)
    )
    (property "MPN" "CR0402-FX-2200GLF" (at 30.48 115.57 0)
      (effects (font (size 1.27 1.27) (thickness 0.15)) (justify left bottom) hide)
    )
    (property "Val" "220R" (at 45.72 101.6 0)
      (effects (font (size 1.27 1.27) (thickness 0.15)) (justify right bottom))
    )
    (property "License" "Apache-2.0" (at 30.48 120.65 0)
      (effects (font (size 1.27 1.27) (thickness 0.15)) (justify left bottom) hide)
    )
    (property "Author" "Antmicro" (at 30.48 123.19 0)
      (effects (font (size 1.27 1.27) (thickness 0.15)) (justify left bottom) hide)
    )
    (property "Tolerance" "1%" (at 30.48 105.41 0)
      (effects (font (size 1.27 1.27)) (justify left bottom) hide)
    )
    (pin "1")
    (pin "2")
    (instances
      (project "scalenode-cm4-baseboard"
        (path ""
          (reference "R21") (unit 1)
        )
      )
    )
  )

  (symbol (lib_id "scalenode-cm4-baseboard:R_220R_0402") (at 50.8 67.31 0) (mirror y) (unit 1)
    (in_bom yes) (on_board yes) (dnp no)
    (property "Reference" "R22" (at 45.72 63.5 0)
      (effects (font (size 1.27 1.27) (thickness 0.15)) (justify right bottom))
    )
    (property "Value" "R_220R_0402" (at 30.48 80.01 0)
      (effects (font (size 1.27 1.27) (thickness 0.15)) (justify left bottom) hide)
    )
    (property "Footprint" "scalenode-cm4-baseboard-footprints:R_0402_1005Metric" (at 30.48 82.55 0)
      (effects (font (size 1.27 1.27) (thickness 0.15)) (justify left bottom) hide)
    )
    (property "Datasheet" "https://www.bourns.com/docs/product-datasheets/cr.pdf" (at 30.48 85.09 0)
      (effects (font (size 1.27 1.27) (thickness 0.15)) (justify left bottom) hide)
    )
    (property "Manufacturer" "Bourns" (at 30.48 90.17 0)
      (effects (font (size 1.27 1.27) (thickness 0.15)) (justify left bottom) hide)
    )
    (property "MPN" "CR0402-FX-2200GLF" (at 30.48 87.63 0)
      (effects (font (size 1.27 1.27) (thickness 0.15)) (justify left bottom) hide)
    )
    (property "Val" "220R" (at 45.72 66.04 0)
      (effects (font (size 1.27 1.27) (thickness 0.15)) (justify right bottom))
    )
    (property "License" "Apache-2.0" (at 30.48 92.71 0)
      (effects (font (size 1.27 1.27) (thickness 0.15)) (justify left bottom) hide)
    )
    (property "Author" "Antmicro" (at 30.48 95.25 0)
      (effects (font (size 1.27 1.27) (thickness 0.15)) (justify left bottom) hide)
    )
    (property "Tolerance" "1%" (at 30.48 77.47 0)
      (effects (font (size 1.27 1.27)) (justify left bottom) hide)
    )
    (pin "1")
    (pin "2")
    (instances
      (project "scalenode-cm4-baseboard"
        (path ""
          (reference "R22") (unit 1)
        )
      )
    )
  )

  (symbol (lib_id "scalenode-cm4-baseboard:H6096NL") (at 210.82 63.5 0) (mirror y) (unit 1)
    (in_bom yes) (on_board yes) (dnp no) (fields_autoplaced)
    (property "Reference" "L3" (at 203.0936 55.88 0)
      (effects (font (size 1.27 1.27) (thickness 0.15)) (justify left bottom))
    )
    (property "Value" "H6096NL" (at 173.99 71.12 0)
      (effects (font (size 1.27 1.27) (thickness 0.15)) (justify left bottom) hide)
    )
    (property "Footprint" "scalenode-cm4-baseboard-footprints:SOIC127P1594X685-24N" (at 173.99 73.66 0)
      (effects (font (size 1.27 1.27) (thickness 0.15)) (justify left bottom) hide)
    )
    (property "Datasheet" "https://www.arrow.com/en/products/h6096nl/pulse-electronics-corporation" (at 173.99 76.2 0)
      (effects (font (size 1.27 1.27) (thickness 0.15)) (justify left bottom) hide)
    )
    (property "Description" "Common Mode Chokes / Filters 1000Base-T SMD PoE+ 350uH .3Ohms 1-Port" (at 173.99 78.74 0)
      (effects (font (size 1.27 1.27) (thickness 0.15)) (justify left bottom) hide)
    )
    (property "MPN" "H6096NL" (at 203.0936 58.42 0)
      (effects (font (size 1.27 1.27) (thickness 0.15)) (justify left bottom))
    )
    (property "Manufacturer" "Pulse Electronics" (at 173.99 81.28 0)
      (effects (font (size 1.27 1.27) (thickness 0.15)) (justify left bottom) hide)
    )
    (property "Author" "Antmicro" (at 173.99 83.82 0)
      (effects (font (size 1.27 1.27) (thickness 0.15)) (justify left bottom) hide)
    )
    (property "License" "Apache-2.0" (at 173.99 86.36 0)
      (effects (font (size 1.27 1.27) (thickness 0.15)) (justify left bottom) hide)
    )
    (pin "1")
    (pin "10")
    (pin "11")
    (pin "12")
    (pin "13")
    (pin "14")
    (pin "15")
    (pin "16")
    (pin "17")
    (pin "18")
    (pin "19")
    (pin "2")
    (pin "20")
    (pin "21")
    (pin "22")
    (pin "23")
    (pin "24")
    (pin "3")
    (pin "4")
    (pin "5")
    (pin "6")
    (pin "7")
    (pin "8")
    (pin "9")
    (instances
      (project "scalenode-cm4-baseboard"
        (path ""
          (reference "L3") (unit 1)
        )
      )
    )
  )

  (symbol (lib_id "scalenode-cm4-baseboard:R_75R_0402") (at 223.52 63.5 180) (unit 1)
    (in_bom yes) (on_board yes) (dnp no)
    (property "Reference" "R27" (at 218.44 60.96 0)
      (effects (font (size 1.27 1.27) (thickness 0.15)) (justify left bottom))
    )
    (property "Value" "R_75R_0402" (at 203.2 50.8 0)
      (effects (font (size 1.27 1.27) (thickness 0.15)) (justify left bottom) hide)
    )
    (property "Footprint" "scalenode-cm4-baseboard-footprints:R_0402_1005Metric" (at 203.2 48.26 0)
      (effects (font (size 1.27 1.27) (thickness 0.15)) (justify left bottom) hide)
    )
    (property "Datasheet" "https://www.bourns.com/docs/product-datasheets/cr.pdf" (at 203.2 45.72 0)
      (effects (font (size 1.27 1.27) (thickness 0.15)) (justify left bottom) hide)
    )
    (property "Manufacturer" "Bourns" (at 203.2 40.64 0)
      (effects (font (size 1.27 1.27) (thickness 0.15)) (justify left bottom) hide)
    )
    (property "MPN" "CR0402-FX-75R0GLF" (at 203.2 43.18 0)
      (effects (font (size 1.27 1.27) (thickness 0.15)) (justify left bottom) hide)
    )
    (property "Val" "75R" (at 227.33 60.96 0)
      (effects (font (size 1.27 1.27) (thickness 0.15)) (justify left bottom))
    )
    (property "License" "Apache-2.0" (at 203.2 38.1 0)
      (effects (font (size 1.27 1.27) (thickness 0.15)) (justify left bottom) hide)
    )
    (property "Author" "Antmicro" (at 203.2 35.56 0)
      (effects (font (size 1.27 1.27) (thickness 0.15)) (justify left bottom) hide)
    )
    (property "Tolerance" "1%" (at 203.2 53.34 0)
      (effects (font (size 1.27 1.27)) (justify left bottom) hide)
    )
    (pin "1")
    (pin "2")
    (instances
      (project "scalenode-cm4-baseboard"
        (path ""
          (reference "R27") (unit 1)
        )
      )
    )
  )

  (symbol (lib_id "scalenode-cm4-baseboard:R_75R_0402") (at 223.52 73.66 180) (unit 1)
    (in_bom yes) (on_board yes) (dnp no)
    (property "Reference" "R28" (at 218.44 71.12 0)
      (effects (font (size 1.27 1.27) (thickness 0.15)) (justify left bottom))
    )
    (property "Value" "R_75R_0402" (at 203.2 60.96 0)
      (effects (font (size 1.27 1.27) (thickness 0.15)) (justify left bottom) hide)
    )
    (property "Footprint" "scalenode-cm4-baseboard-footprints:R_0402_1005Metric" (at 203.2 58.42 0)
      (effects (font (size 1.27 1.27) (thickness 0.15)) (justify left bottom) hide)
    )
    (property "Datasheet" "https://www.bourns.com/docs/product-datasheets/cr.pdf" (at 203.2 55.88 0)
      (effects (font (size 1.27 1.27) (thickness 0.15)) (justify left bottom) hide)
    )
    (property "Manufacturer" "Bourns" (at 203.2 50.8 0)
      (effects (font (size 1.27 1.27) (thickness 0.15)) (justify left bottom) hide)
    )
    (property "MPN" "CR0402-FX-75R0GLF" (at 203.2 53.34 0)
      (effects (font (size 1.27 1.27) (thickness 0.15)) (justify left bottom) hide)
    )
    (property "Val" "75R" (at 227.33 71.12 0)
      (effects (font (size 1.27 1.27) (thickness 0.15)) (justify left bottom))
    )
    (property "License" "Apache-2.0" (at 203.2 48.26 0)
      (effects (font (size 1.27 1.27) (thickness 0.15)) (justify left bottom) hide)
    )
    (property "Author" "Antmicro" (at 203.2 45.72 0)
      (effects (font (size 1.27 1.27) (thickness 0.15)) (justify left bottom) hide)
    )
    (property "Tolerance" "1%" (at 203.2 63.5 0)
      (effects (font (size 1.27 1.27)) (justify left bottom) hide)
    )
    (pin "1")
    (pin "2")
    (instances
      (project "scalenode-cm4-baseboard"
        (path ""
          (reference "R28") (unit 1)
        )
      )
    )
  )

  (symbol (lib_id "scalenode-cm4-baseboard:R_75R_0402") (at 223.52 83.82 180) (unit 1)
    (in_bom yes) (on_board yes) (dnp no)
    (property "Reference" "R29" (at 218.44 81.28 0)
      (effects (font (size 1.27 1.27) (thickness 0.15)) (justify left bottom))
    )
    (property "Value" "R_75R_0402" (at 203.2 71.12 0)
      (effects (font (size 1.27 1.27) (thickness 0.15)) (justify left bottom) hide)
    )
    (property "Footprint" "scalenode-cm4-baseboard-footprints:R_0402_1005Metric" (at 203.2 68.58 0)
      (effects (font (size 1.27 1.27) (thickness 0.15)) (justify left bottom) hide)
    )
    (property "Datasheet" "https://www.bourns.com/docs/product-datasheets/cr.pdf" (at 203.2 66.04 0)
      (effects (font (size 1.27 1.27) (thickness 0.15)) (justify left bottom) hide)
    )
    (property "Manufacturer" "Bourns" (at 203.2 60.96 0)
      (effects (font (size 1.27 1.27) (thickness 0.15)) (justify left bottom) hide)
    )
    (property "MPN" "CR0402-FX-75R0GLF" (at 203.2 63.5 0)
      (effects (font (size 1.27 1.27) (thickness 0.15)) (justify left bottom) hide)
    )
    (property "Val" "75R" (at 227.33 81.28 0)
      (effects (font (size 1.27 1.27) (thickness 0.15)) (justify left bottom))
    )
    (property "License" "Apache-2.0" (at 203.2 58.42 0)
      (effects (font (size 1.27 1.27) (thickness 0.15)) (justify left bottom) hide)
    )
    (property "Author" "Antmicro" (at 203.2 55.88 0)
      (effects (font (size 1.27 1.27) (thickness 0.15)) (justify left bottom) hide)
    )
    (property "Tolerance" "1%" (at 203.2 73.66 0)
      (effects (font (size 1.27 1.27)) (justify left bottom) hide)
    )
    (pin "1")
    (pin "2")
    (instances
      (project "scalenode-cm4-baseboard"
        (path ""
          (reference "R29") (unit 1)
        )
      )
    )
  )

  (symbol (lib_id "scalenode-cm4-baseboard:R_75R_0402") (at 223.52 93.98 180) (unit 1)
    (in_bom yes) (on_board yes) (dnp no)
    (property "Reference" "R30" (at 218.44 91.44 0)
      (effects (font (size 1.27 1.27) (thickness 0.15)) (justify left bottom))
    )
    (property "Value" "R_75R_0402" (at 203.2 81.28 0)
      (effects (font (size 1.27 1.27) (thickness 0.15)) (justify left bottom) hide)
    )
    (property "Footprint" "scalenode-cm4-baseboard-footprints:R_0402_1005Metric" (at 203.2 78.74 0)
      (effects (font (size 1.27 1.27) (thickness 0.15)) (justify left bottom) hide)
    )
    (property "Datasheet" "https://www.bourns.com/docs/product-datasheets/cr.pdf" (at 203.2 76.2 0)
      (effects (font (size 1.27 1.27) (thickness 0.15)) (justify left bottom) hide)
    )
    (property "Manufacturer" "Bourns" (at 203.2 71.12 0)
      (effects (font (size 1.27 1.27) (thickness 0.15)) (justify left bottom) hide)
    )
    (property "MPN" "CR0402-FX-75R0GLF" (at 203.2 73.66 0)
      (effects (font (size 1.27 1.27) (thickness 0.15)) (justify left bottom) hide)
    )
    (property "Val" "75R" (at 227.33 91.44 0)
      (effects (font (size 1.27 1.27) (thickness 0.15)) (justify left bottom))
    )
    (property "License" "Apache-2.0" (at 203.2 68.58 0)
      (effects (font (size 1.27 1.27) (thickness 0.15)) (justify left bottom) hide)
    )
    (property "Author" "Antmicro" (at 203.2 66.04 0)
      (effects (font (size 1.27 1.27) (thickness 0.15)) (justify left bottom) hide)
    )
    (property "Tolerance" "1%" (at 203.2 83.82 0)
      (effects (font (size 1.27 1.27)) (justify left bottom) hide)
    )
    (pin "1")
    (pin "2")
    (instances
      (project "scalenode-cm4-baseboard"
        (path ""
          (reference "R30") (unit 1)
        )
      )
    )
  )

  (symbol (lib_id "scalenode-cm4-baseboard:C_1n_1210_2kV") (at 228.6 109.22 270) (mirror x) (unit 1)
    (in_bom yes) (on_board yes) (dnp no) (fields_autoplaced)
    (property "Reference" "C25" (at 231.14 105.4035 90)
      (effects (font (size 1.27 1.27) (thickness 0.15)) (justify left bottom))
    )
    (property "Value" "C_1n_1210_2kV" (at 218.44 88.9 0)
      (effects (font (size 1.27 1.27) (thickness 0.15)) (justify left bottom) hide)
    )
    (property "Footprint" "scalenode-cm4-baseboard-footprints:C_1210_3225Metric" (at 215.9 88.9 0)
      (effects (font (size 1.27 1.27) (thickness 0.15)) (justify left bottom) hide)
    )
    (property "Datasheet" "https://www.kemet.com/en/us/capacitors/product/C1210C102KGRACTU.html" (at 213.36 88.9 0)
      (effects (font (size 1.27 1.27) (thickness 0.15)) (justify left bottom) hide)
    )
    (property "Manufacturer" "KEMET" (at 208.28 88.9 0)
      (effects (font (size 1.27 1.27) (thickness 0.15)) (justify left bottom) hide)
    )
    (property "MPN" "C1210C102KGRACTU" (at 210.82 88.9 0)
      (effects (font (size 1.27 1.27) (thickness 0.15)) (justify left bottom) hide)
    )
    (property "Val" "1n" (at 231.14 107.9435 90)
      (effects (font (size 1.27 1.27) (thickness 0.15)) (justify left bottom))
    )
    (property "License" "Apache-2.0" (at 205.74 88.9 0)
      (effects (font (size 1.27 1.27) (thickness 0.15)) (justify left bottom) hide)
    )
    (property "Author" "Antmicro" (at 203.2 88.9 0)
      (effects (font (size 1.27 1.27) (thickness 0.15)) (justify left bottom) hide)
    )
    (property "Voltage" "2kV" (at 200.66 88.9 0)
      (effects (font (size 1.27 1.27)) (justify left bottom) hide)
    )
    (property "Dielectric" "" (at 198.12 88.9 0)
      (effects (font (size 1.27 1.27)) (justify left bottom) hide)
    )
    (pin "1")
    (pin "2")
    (instances
      (project "scalenode-cm4-baseboard"
        (path ""
          (reference "C25") (unit 1)
        )
      )
    )
  )

  (symbol (lib_id "scalenode-cm4-baseboard:GND") (at 228.6 133.35 0) (unit 1)
    (in_bom yes) (on_board yes) (dnp no) (fields_autoplaced)
    (property "Reference" "#PWR0105" (at 237.49 135.89 0)
      (effects (font (size 1.27 1.27) (thickness 0.15)) (justify left bottom) hide)
    )
    (property "Value" "GND" (at 226.5898 138.43 0)
      (effects (font (size 1.27 1.27) (thickness 0.15)) (justify left bottom))
    )
    (property "Footprint" "" (at 237.49 140.97 0)
      (effects (font (size 1.27 1.27) (thickness 0.15)) (justify left bottom) hide)
    )
    (property "Datasheet" "" (at 237.49 146.05 0)
      (effects (font (size 1.27 1.27) (thickness 0.15)) (justify left bottom) hide)
    )
    (property "Author" "Antmicro" (at 237.49 140.97 0)
      (effects (font (size 1.27 1.27) (thickness 0.15)) (justify left bottom) hide)
    )
    (property "License" "Apache-2.0" (at 237.49 143.51 0)
      (effects (font (size 1.27 1.27) (thickness 0.15)) (justify left bottom) hide)
    )
    (pin "1")
    (instances
      (project "scalenode-cm4-baseboard"
        (path ""
          (reference "#PWR0105") (unit 1)
        )
      )
    )
  )

  (symbol (lib_id "scalenode-cm4-baseboard:Earth") (at 196.85 134.62 0) (unit 1)
    (in_bom yes) (on_board yes) (dnp no) (fields_autoplaced)
    (property "Reference" "#PWR0107" (at 196.85 140.97 0)
      (effects (font (size 1.27 1.27)) hide)
    )
    (property "Value" "Earth" (at 196.85 138.43 0)
      (effects (font (size 1.27 1.27)) hide)
    )
    (property "Footprint" "" (at 196.85 134.62 0)
      (effects (font (size 1.27 1.27)) hide)
    )
    (property "Datasheet" "" (at 196.85 134.62 0)
      (effects (font (size 1.27 1.27)) hide)
    )
    (pin "1")
    (instances
      (project "scalenode-cm4-baseboard"
        (path ""
          (reference "#PWR0107") (unit 1)
        )
      )
    )
  )

  (symbol (lib_id "scalenode-cm4-baseboard:C_1n_1210_2kV") (at 208.28 128.27 0) (mirror y) (unit 1)
    (in_bom yes) (on_board yes) (dnp no)
    (property "Reference" "C50" (at 203.2 132.08 0)
      (effects (font (size 1.27 1.27) (thickness 0.15)) (justify right bottom))
    )
    (property "Value" "C_1n_1210_2kV" (at 187.96 138.43 0)
      (effects (font (size 1.27 1.27) (thickness 0.15)) (justify left bottom) hide)
    )
    (property "Footprint" "scalenode-cm4-baseboard-footprints:C_1210_3225Metric" (at 187.96 140.97 0)
      (effects (font (size 1.27 1.27) (thickness 0.15)) (justify left bottom) hide)
    )
    (property "Datasheet" "https://www.kemet.com/en/us/capacitors/product/C1210C102KGRACTU.html" (at 187.96 143.51 0)
      (effects (font (size 1.27 1.27) (thickness 0.15)) (justify left bottom) hide)
    )
    (property "Manufacturer" "KEMET" (at 187.96 148.59 0)
      (effects (font (size 1.27 1.27) (thickness 0.15)) (justify left bottom) hide)
    )
    (property "MPN" "C1210C102KGRACTU" (at 187.96 146.05 0)
      (effects (font (size 1.27 1.27) (thickness 0.15)) (justify left bottom) hide)
    )
    (property "Val" "1n" (at 203.2 133.35 0)
      (effects (font (size 1.27 1.27) (thickness 0.15)) (justify right))
    )
    (property "License" "Apache-2.0" (at 187.96 151.13 0)
      (effects (font (size 1.27 1.27) (thickness 0.15)) (justify left bottom) hide)
    )
    (property "Author" "Antmicro" (at 187.96 153.67 0)
      (effects (font (size 1.27 1.27) (thickness 0.15)) (justify left bottom) hide)
    )
    (property "Voltage" "2kV" (at 187.96 156.21 0)
      (effects (font (size 1.27 1.27)) (justify left bottom) hide)
    )
    (property "Dielectric" "" (at 187.96 158.75 0)
      (effects (font (size 1.27 1.27)) (justify left bottom) hide)
    )
    (pin "1")
    (pin "2")
    (instances
      (project "scalenode-cm4-baseboard"
        (path ""
          (reference "C50") (unit 1)
        )
      )
    )
  )

  (symbol (lib_id "scalenode-cm4-baseboard:GND") (at 214.63 133.35 0) (unit 1)
    (in_bom yes) (on_board yes) (dnp no) (fields_autoplaced)
    (property "Reference" "#PWR0108" (at 223.52 135.89 0)
      (effects (font (size 1.27 1.27) (thickness 0.15)) (justify left bottom) hide)
    )
    (property "Value" "GND" (at 212.6198 138.43 0)
      (effects (font (size 1.27 1.27) (thickness 0.15)) (justify left bottom))
    )
    (property "Footprint" "" (at 223.52 140.97 0)
      (effects (font (size 1.27 1.27) (thickness 0.15)) (justify left bottom) hide)
    )
    (property "Datasheet" "" (at 223.52 146.05 0)
      (effects (font (size 1.27 1.27) (thickness 0.15)) (justify left bottom) hide)
    )
    (property "Author" "Antmicro" (at 223.52 140.97 0)
      (effects (font (size 1.27 1.27) (thickness 0.15)) (justify left bottom) hide)
    )
    (property "License" "Apache-2.0" (at 223.52 143.51 0)
      (effects (font (size 1.27 1.27) (thickness 0.15)) (justify left bottom) hide)
    )
    (pin "1")
    (instances
      (project "scalenode-cm4-baseboard"
        (path ""
          (reference "#PWR0108") (unit 1)
        )
      )
    )
  )

  (symbol (lib_id "scalenode-cm4-baseboard:R_0R_1206") (at 203.2 121.92 0) (unit 1)
    (in_bom no) (on_board yes) (dnp yes)
    (property "Reference" "R17" (at 203.2 118.11 0)
      (effects (font (size 1.27 1.27) (thickness 0.15)) (justify left bottom))
    )
    (property "Value" "R_0R_1206" (at 223.52 134.62 0)
      (effects (font (size 1.27 1.27) (thickness 0.15)) (justify left bottom) hide)
    )
    (property "Footprint" "scalenode-cm4-baseboard-footprints:R_1206_3216Metric" (at 223.52 137.16 0)
      (effects (font (size 1.27 1.27) (thickness 0.15)) (justify left bottom) hide)
    )
    (property "Datasheet" "https://www.farnell.com/datasheets/2860635.pdf" (at 223.52 139.7 0)
      (effects (font (size 1.27 1.27) (thickness 0.15)) (justify left bottom) hide)
    )
    (property "Manufacturer" "Multicomp Pro" (at 223.52 144.78 0)
      (effects (font (size 1.27 1.27) (thickness 0.15)) (justify left bottom) hide)
    )
    (property "MPN" "MCMR12X000_PTL" (at 223.52 142.24 0)
      (effects (font (size 1.27 1.27) (thickness 0.15)) (justify left bottom) hide)
    )
    (property "Val" "0R" (at 203.2 120.65 0)
      (effects (font (size 1.27 1.27) (thickness 0.15)) (justify left bottom))
    )
    (property "DNP" "DNP" (at 205.74 121.92 0)
      (effects (font (size 1 1)))
    )
    (property "License" "Apache-2.0" (at 223.52 147.32 0)
      (effects (font (size 1.27 1.27) (thickness 0.15)) (justify left bottom) hide)
    )
    (property "Author" "Antmicro" (at 223.52 149.86 0)
      (effects (font (size 1.27 1.27) (thickness 0.15)) (justify left bottom) hide)
    )
    (property "Tolerance" "~" (at 223.52 132.08 0)
      (effects (font (size 1.27 1.27)) (justify left bottom) hide)
    )
    (property "Current" "2A" (at 223.52 152.4 0)
      (effects (font (size 1.27 1.27) (thickness 0.15)) (justify left bottom) hide)
    )
    (pin "1")
    (pin "2")
    (instances
      (project "scalenode-cm4-baseboard"
        (path ""
          (reference "R17") (unit 1)
        )
      )
    )
  )

  (symbol (lib_id "scalenode-cm4-baseboard:SS-74800-144") (at 53.34 67.31 0) (unit 1)
    (in_bom yes) (on_board yes) (dnp no) (fields_autoplaced)
    (property "Reference" "J6" (at 55.17 59.69 0)
      (effects (font (size 1.27 1.27) (thickness 0.15)) (justify left bottom))
    )
    (property "Value" "SS-74800-144" (at 86.36 74.93 0)
      (effects (font (size 1.27 1.27) (thickness 0.15)) (justify left bottom) hide)
    )
    (property "Footprint" "scalenode-cm4-baseboard-footprints:Ethernet_Jack_SS-74800-144" (at 86.36 77.47 0)
      (effects (font (size 1.27 1.27) (thickness 0.15)) (justify left bottom) hide)
    )
    (property "Datasheet" "https://www.belfuse.com/resources/drawings/stewartconnector/dr-STW-SS-74800-144.pdf" (at 86.36 80.01 0)
      (effects (font (size 1.27 1.27) (thickness 0.15)) (justify left bottom) hide)
    )
    (property "MPN" "SS-74800-144" (at 55.17 62.23 0)
      (effects (font (size 1.27 1.27) (thickness 0.15)) (justify left bottom))
    )
    (property "Manufacturer" "Bel" (at 86.36 82.55 0)
      (effects (font (size 1.27 1.27) (thickness 0.15)) (justify left bottom) hide)
    )
    (property "Author" "Antmicro" (at 86.36 85.09 0)
      (effects (font (size 1.27 1.27) (thickness 0.15)) (justify left bottom) hide)
    )
    (property "License" "Apache-2.0" (at 86.36 87.63 0)
      (effects (font (size 1.27 1.27) (thickness 0.15)) (justify left bottom) hide)
    )
    (pin "1")
    (pin "10")
    (pin "11")
    (pin "12")
    (pin "2")
    (pin "3")
    (pin "4")
    (pin "5")
    (pin "6")
    (pin "7")
    (pin "8")
    (pin "9")
    (pin "SH")
    (instances
      (project "scalenode-cm4-baseboard"
        (path ""
          (reference "J6") (unit 1)
        )
      )
    )
  )

  (symbol (lib_id "scalenode-cm4-baseboard:Earth") (at 73.66 87.63 0) (unit 1)
    (in_bom yes) (on_board yes) (dnp no) (fields_autoplaced)
    (property "Reference" "#PWR0113" (at 73.66 93.98 0)
      (effects (font (size 1.27 1.27)) hide)
    )
    (property "Value" "Earth" (at 73.66 91.44 0)
      (effects (font (size 1.27 1.27)) hide)
    )
    (property "Footprint" "" (at 73.66 87.63 0)
      (effects (font (size 1.27 1.27)) hide)
    )
    (property "Datasheet" "" (at 73.66 87.63 0)
      (effects (font (size 1.27 1.27)) hide)
    )
    (pin "1")
    (instances
      (project "scalenode-cm4-baseboard"
        (path ""
          (reference "#PWR0113") (unit 1)
        )
      )
    )
  )

  (symbol (lib_id "scalenode-cm4-baseboard:R_1k3_0402") (at 97.79 243.84 0) (unit 1)
    (in_bom no) (on_board yes) (dnp yes)
    (property "Reference" "R37" (at 95.25 242.57 0)
      (effects (font (size 1.27 1.27) (thickness 0.15)) (justify left bottom))
    )
    (property "Value" "R_1k3_0402" (at 118.11 256.54 0)
      (effects (font (size 1.27 1.27) (thickness 0.15)) (justify left bottom) hide)
    )
    (property "Footprint" "scalenode-cm4-baseboard-footprints:R_0402_1005Metric" (at 118.11 259.08 0)
      (effects (font (size 1.27 1.27) (thickness 0.15)) (justify left bottom) hide)
    )
    (property "Datasheet" "https://www.bourns.com/docs/product-datasheets/cr.pdf" (at 118.11 261.62 0)
      (effects (font (size 1.27 1.27) (thickness 0.15)) (justify left bottom) hide)
    )
    (property "Manufacturer" "Bourns" (at 118.11 266.7 0)
      (effects (font (size 1.27 1.27) (thickness 0.15)) (justify left bottom) hide)
    )
    (property "MPN" "CR0402-FX-1301GLF" (at 118.11 264.16 0)
      (effects (font (size 1.27 1.27) (thickness 0.15)) (justify left bottom) hide)
    )
    (property "Val" "1k3" (at 101.6 242.57 0)
      (effects (font (size 1.27 1.27) (thickness 0.15)) (justify left bottom))
    )
    (property "DNP" "DNP" (at 100.33 243.84 0)
      (effects (font (size 1 1)))
    )
    (property "License" "Apache-2.0" (at 118.11 269.24 0)
      (effects (font (size 1.27 1.27) (thickness 0.15)) (justify left bottom) hide)
    )
    (property "Author" "Antmicro" (at 118.11 271.78 0)
      (effects (font (size 1.27 1.27) (thickness 0.15)) (justify left bottom) hide)
    )
    (property "Tolerance" "1%" (at 118.11 254 0)
      (effects (font (size 1.27 1.27)) (justify left bottom) hide)
    )
    (pin "1")
    (pin "2")
    (instances
      (project "scalenode-cm4-baseboard"
        (path ""
          (reference "R37") (unit 1)
        )
      )
    )
  )

  (symbol (lib_id "scalenode-cm4-baseboard:C_22u_100V_2220") (at 222.25 194.31 90) (unit 1)
    (in_bom yes) (on_board yes) (dnp no)
    (property "Reference" "C28" (at 222.25 193.04 90)
      (effects (font (size 1.27 1.27) (thickness 0.15)) (justify left bottom))
    )
    (property "Value" "C_22u_100V_2220" (at 232.41 173.99 0)
      (effects (font (size 1.27 1.27) (thickness 0.15)) (justify left bottom) hide)
    )
    (property "Footprint" "scalenode-cm4-baseboard-footprints:C_2220_5650Metric" (at 234.95 173.99 0)
      (effects (font (size 1.27 1.27) (thickness 0.15)) (justify left bottom) hide)
    )
    (property "Datasheet" "https://product.tdk.com/en/search/capacitor/ceramic/mlcc/info?part_no=C5750X7S2A226M280KB" (at 237.49 173.99 0)
      (effects (font (size 1.27 1.27) (thickness 0.15)) (justify left bottom) hide)
    )
    (property "Manufacturer" "TDK" (at 242.57 173.99 0)
      (effects (font (size 1.27 1.27) (thickness 0.15)) (justify left bottom) hide)
    )
    (property "MPN" "C5750X7S2A226M280KB" (at 240.03 173.99 0)
      (effects (font (size 1.27 1.27) (thickness 0.15)) (justify left bottom) hide)
    )
    (property "Val" "22u" (at 222.25 190.5 0)
      (effects (font (size 1.27 1.27) (thickness 0.15)) (justify left bottom))
    )
    (property "Author" "Antmicro" (at 247.65 173.99 0)
      (effects (font (size 1.27 1.27) (thickness 0.15)) (justify left bottom) hide)
    )
    (property "License" "Apache-2.0" (at 245.11 173.99 0)
      (effects (font (size 1.27 1.27) (thickness 0.15)) (justify left bottom) hide)
    )
    (property "Voltage" "100V" (at 250.19 173.99 0)
      (effects (font (size 1.27 1.27)) (justify left bottom) hide)
    )
    (property "Dielectric" "X7S" (at 252.73 173.99 0)
      (effects (font (size 1.27 1.27)) (justify left bottom) hide)
    )
    (pin "1")
    (pin "2")
    (instances
      (project "scalenode-cm4-baseboard"
        (path ""
          (reference "C28") (unit 1)
        )
      )
    )
  )

  (symbol (lib_id "scalenode-cm4-baseboard:MB10S") (at 53.34 144.78 0) (unit 1)
    (in_bom yes) (on_board yes) (dnp no) (fields_autoplaced)
    (property "Reference" "D4" (at 58.98 138.43 0)
      (effects (font (size 1.27 1.27) (thickness 0.15)) (justify left bottom))
    )
    (property "Value" "MB10S" (at 81.28 149.86 0)
      (effects (font (size 1.27 1.27) (thickness 0.15)) (justify left bottom) hide)
    )
    (property "Footprint" "scalenode-cm4-baseboard-footprints:SOIC-4_W3.9mm" (at 81.28 152.4 0)
      (effects (font (size 1.27 1.27) (thickness 0.15)) (justify left bottom) hide)
    )
    (property "Datasheet" "http://www.farnell.com/datasheets/2895435.pdf" (at 81.28 154.94 0)
      (effects (font (size 1.27 1.27) (thickness 0.15)) (justify left bottom) hide)
    )
    (property "MPN" "MB10S" (at 58.98 140.97 0)
      (effects (font (size 1.27 1.27) (thickness 0.15)) (justify left bottom))
    )
    (property "Manufacturer" "Multicomp Pro" (at 81.28 160.02 0)
      (effects (font (size 1.27 1.27) (thickness 0.15)) (justify left bottom) hide)
    )
    (property "Author" "Antmicro" (at 81.28 162.56 0)
      (effects (font (size 1.27 1.27) (thickness 0.15)) (justify left bottom) hide)
    )
    (property "License" "Apache-2.0" (at 81.28 165.1 0)
      (effects (font (size 1.27 1.27) (thickness 0.15)) (justify left bottom) hide)
    )
    (pin "1")
    (pin "2")
    (pin "3")
    (pin "4")
    (instances
      (project "scalenode-cm4-baseboard"
        (path ""
          (reference "D4") (unit 1)
        )
      )
    )
  )

  (symbol (lib_id "scalenode-cm4-baseboard:C_100n_0402") (at 321.31 196.85 90) (unit 1)
    (in_bom yes) (on_board yes) (dnp no)
    (property "Reference" "C37" (at 321.31 191.77 90)
      (effects (font (size 1.27 1.27) (thickness 0.15)) (justify left bottom))
    )
    (property "Value" "C_100n_0402" (at 331.47 176.53 0)
      (effects (font (size 1.27 1.27) (thickness 0.15)) (justify left bottom) hide)
    )
    (property "Footprint" "scalenode-cm4-baseboard-footprints:C_0402_1005Metric" (at 334.01 176.53 0)
      (effects (font (size 1.27 1.27) (thickness 0.15)) (justify left bottom) hide)
    )
    (property "Datasheet" "https://www.murata.com/products/productdetail?partno=GRM155R61H104KE14%23" (at 336.55 176.53 0)
      (effects (font (size 1.27 1.27) (thickness 0.15)) (justify left bottom) hide)
    )
    (property "Manufacturer" "Murata" (at 341.63 176.53 0)
      (effects (font (size 1.27 1.27) (thickness 0.15)) (justify left bottom) hide)
    )
    (property "MPN" "GRM155R61H104KE14D" (at 339.09 176.53 0)
      (effects (font (size 1.27 1.27) (thickness 0.15)) (justify left bottom) hide)
    )
    (property "Val" "100n" (at 321.31 195.58 90)
      (effects (font (size 1.27 1.27) (thickness 0.15)) (justify left bottom))
    )
    (property "License" "Apache-2.0" (at 344.17 176.53 0)
      (effects (font (size 1.27 1.27) (thickness 0.15)) (justify left bottom) hide)
    )
    (property "Author" "Antmicro" (at 346.71 176.53 0)
      (effects (font (size 1.27 1.27) (thickness 0.15)) (justify left bottom) hide)
    )
    (property "Voltage" "50V" (at 349.25 176.53 0)
      (effects (font (size 1.27 1.27)) (justify left bottom) hide)
    )
    (property "Dielectric" "X5R" (at 351.79 176.53 0)
      (effects (font (size 1.27 1.27)) (justify left bottom) hide)
    )
    (pin "1")
    (pin "2")
    (instances
      (project "scalenode-cm4-baseboard"
        (path ""
          (reference "C37") (unit 1)
        )
      )
    )
  )

  (symbol (lib_id "scalenode-cm4-baseboard:GNDD") (at 162.56 180.34 0) (unit 1)
    (in_bom yes) (on_board yes) (dnp no) (fields_autoplaced)
    (property "Reference" "#PWR01" (at 177.8 182.88 0)
      (effects (font (size 1.27 1.27) (thickness 0.15)) (justify left bottom) hide)
    )
    (property "Value" "GNDD" (at 159.9148 185.42 0)
      (effects (font (size 1.27 1.27) (thickness 0.15)) (justify left bottom))
    )
    (property "Footprint" "" (at 177.8 190.5 0)
      (effects (font (size 1.27 1.27) (thickness 0.15)) (justify left bottom) hide)
    )
    (property "Datasheet" "" (at 177.8 193.04 0)
      (effects (font (size 1.27 1.27) (thickness 0.15)) (justify left bottom) hide)
    )
    (property "Author" "Antmicro" (at 177.8 187.96 0)
      (effects (font (size 1.27 1.27) (thickness 0.15)) (justify left bottom) hide)
    )
    (property "License" "Apache-2.0" (at 177.8 190.5 0)
      (effects (font (size 1.27 1.27) (thickness 0.15)) (justify left bottom) hide)
    )
    (pin "1")
    (instances
      (project "scalenode-cm4-baseboard"
        (path ""
          (reference "#PWR01") (unit 1)
        )
      )
    )
  )

  (symbol (lib_id "scalenode-cm4-baseboard:TP_1mm_SMD") (at 345.44 199.39 90) (unit 1)
    (in_bom yes) (on_board yes) (dnp no)
    (property "Reference" "TP4" (at 345.44 195.58 90)
      (effects (font (size 1.27 1.27) (thickness 0.15)) (justify top))
    )
    (property "Value" "TP_1mm_SMD" (at 353.06 184.15 0)
      (effects (font (size 1.27 1.27) (thickness 0.15)) (justify left bottom) hide)
    )
    (property "Footprint" "scalenode-cm4-baseboard-footprints:TP_SMD_1mm" (at 355.6 184.15 0)
      (effects (font (size 1.27 1.27) (thickness 0.15)) (justify left bottom) hide)
    )
    (property "Datasheet" "" (at 358.14 184.15 0)
      (effects (font (size 1.27 1.27) (thickness 0.15)) (justify left bottom) hide)
    )
    (property "Author" "Antmicro" (at 360.68 184.15 0)
      (effects (font (size 1.27 1.27) (thickness 0.15)) (justify left bottom) hide)
    )
    (property "License" "Apache-2.0" (at 363.22 184.15 0)
      (effects (font (size 1.27 1.27) (thickness 0.15)) (justify left bottom) hide)
    )
    (property "MPN" "" (at 345.44 199.39 0)
      (effects (font (size 1.27 1.27)) hide)
    )
    (property "Manufacturer" "" (at 345.44 199.39 0)
      (effects (font (size 1.27 1.27)) hide)
    )
    (pin "1")
    (instances
      (project "scalenode-cm4-baseboard"
        (path ""
          (reference "TP4") (unit 1)
        )
      )
    )
  )

  (symbol (lib_id "scalenode-cm4-baseboard:LED_G_0603_KP-1608CGCK") (at 242.57 187.96 270) (unit 1)
    (in_bom yes) (on_board yes) (dnp no)
    (property "Reference" "D7" (at 243.84 190.5 90)
      (effects (font (size 1.27 1.27) (thickness 0.15)) (justify left bottom))
    )
    (property "Value" "LED_G_0603_KP-1608CGCK" (at 246.38 193.0399 90)
      (effects (font (size 1.27 1.27) (thickness 0.15)) (justify left bottom) hide)
    )
    (property "Footprint" "scalenode-cm4-baseboard-footprints:LED_0603_1608Metric_G" (at 232.41 210.82 0)
      (effects (font (size 1.27 1.27) (thickness 0.15)) (justify left bottom) hide)
    )
    (property "Datasheet" "http://www.farnell.com/datasheets/2045956.pdf" (at 229.87 210.82 0)
      (effects (font (size 1.27 1.27) (thickness 0.15)) (justify left bottom) hide)
    )
    (property "MPN" "KP-1608CGCK" (at 227.33 210.82 0)
      (effects (font (size 1.27 1.27) (thickness 0.15)) (justify left bottom) hide)
    )
    (property "Manufacturer" "Kingbright" (at 224.79 210.82 0)
      (effects (font (size 1.27 1.27) (thickness 0.15)) (justify left bottom) hide)
    )
    (property "Author" "Antmicro" (at 222.25 210.82 0)
      (effects (font (size 1.27 1.27) (thickness 0.15)) (justify left bottom) hide)
    )
    (property "License" "Apache-2.0" (at 219.71 210.82 0)
      (effects (font (size 1.27 1.27) (thickness 0.15)) (justify left bottom) hide)
    )
    (pin "1")
    (pin "2")
    (instances
      (project "scalenode-cm4-baseboard"
        (path ""
          (reference "D7") (unit 1)
        )
      )
    )
  )

  (symbol (lib_id "scalenode-cm4-baseboard:TP_1mm_SMD") (at 266.7 175.26 90) (unit 1)
    (in_bom yes) (on_board yes) (dnp no)
    (property "Reference" "TP3" (at 271.78 170.18 90)
      (effects (font (size 1.27 1.27) (thickness 0.15)) (justify left bottom))
    )
    (property "Value" "TP_1mm_SMD" (at 274.32 160.02 0)
      (effects (font (size 1.27 1.27) (thickness 0.15)) (justify left bottom) hide)
    )
    (property "Footprint" "scalenode-cm4-baseboard-footprints:TP_SMD_1mm" (at 276.86 160.02 0)
      (effects (font (size 1.27 1.27) (thickness 0.15)) (justify left bottom) hide)
    )
    (property "Datasheet" "" (at 279.4 160.02 0)
      (effects (font (size 1.27 1.27) (thickness 0.15)) (justify left bottom) hide)
    )
    (property "Author" "Antmicro" (at 281.94 160.02 0)
      (effects (font (size 1.27 1.27) (thickness 0.15)) (justify left bottom) hide)
    )
    (property "License" "Apache-2.0" (at 284.48 160.02 0)
      (effects (font (size 1.27 1.27) (thickness 0.15)) (justify left bottom) hide)
    )
    (property "MPN" "" (at 266.7 175.26 0)
      (effects (font (size 1.27 1.27)) hide)
    )
    (property "Manufacturer" "" (at 266.7 175.26 0)
      (effects (font (size 1.27 1.27)) hide)
    )
    (pin "1")
    (instances
      (project "scalenode-cm4-baseboard"
        (path ""
          (reference "TP3") (unit 1)
        )
      )
    )
  )

  (symbol (lib_id "scalenode-cm4-baseboard:R_15k_0603") (at 254 191.77 90) (unit 1)
    (in_bom yes) (on_board yes) (dnp no)
    (property "Reference" "R34" (at 255.27 189.23 90)
      (effects (font (size 1.27 1.27) (thickness 0.15)) (justify right top))
    )
    (property "Value" "R_15k_0603" (at 266.7 171.45 0)
      (effects (font (size 1.27 1.27) (thickness 0.15)) (justify left bottom) hide)
    )
    (property "Footprint" "scalenode-cm4-baseboard-footprints:R_0603_1608Metric" (at 269.24 171.45 0)
      (effects (font (size 1.27 1.27) (thickness 0.15)) (justify left bottom) hide)
    )
    (property "Datasheet" "https://www.bourns.com/docs/product-datasheets/cr.pdf" (at 271.78 171.45 0)
      (effects (font (size 1.27 1.27) (thickness 0.15)) (justify left bottom) hide)
    )
    (property "Manufacturer" "Bourns" (at 276.86 171.45 0)
      (effects (font (size 1.27 1.27) (thickness 0.15)) (justify left bottom) hide)
    )
    (property "MPN" "CR0603-FX-1502ELF" (at 274.32 171.45 0)
      (effects (font (size 1.27 1.27) (thickness 0.15)) (justify left bottom) hide)
    )
    (property "Val" "15k" (at 255.27 189.23 90)
      (effects (font (size 1.27 1.27) (thickness 0.15)) (justify right bottom))
    )
    (property "License" "Apache-2.0" (at 279.4 171.45 0)
      (effects (font (size 1.27 1.27) (thickness 0.15)) (justify left bottom) hide)
    )
    (property "Author" "Antmicro" (at 281.94 171.45 0)
      (effects (font (size 1.27 1.27) (thickness 0.15)) (justify left bottom) hide)
    )
    (property "Tolerance" "1%" (at 264.16 171.45 0)
      (effects (font (size 1.27 1.27)) (justify left bottom) hide)
    )
    (pin "1")
    (pin "2")
    (instances
      (project "scalenode-cm4-baseboard"
        (path ""
          (reference "R34") (unit 1)
        )
      )
    )
  )

  (symbol (lib_id "scalenode-cm4-baseboard:R_24k9_0402") (at 127 162.56 0) (unit 1)
    (in_bom yes) (on_board yes) (dnp no)
    (property "Reference" "R24" (at 127 158.75 0)
      (effects (font (size 1.27 1.27) (thickness 0.15)) (justify left bottom))
    )
    (property "Value" "R_24k9_0402" (at 147.32 175.26 0)
      (effects (font (size 1.27 1.27) (thickness 0.15)) (justify left bottom) hide)
    )
    (property "Footprint" "scalenode-cm4-baseboard-footprints:R_0402_1005Metric" (at 147.32 177.8 0)
      (effects (font (size 1.27 1.27) (thickness 0.15)) (justify left bottom) hide)
    )
    (property "Datasheet" "https://www.bourns.com/docs/product-datasheets/cr.pdf" (at 147.32 180.34 0)
      (effects (font (size 1.27 1.27) (thickness 0.15)) (justify left bottom) hide)
    )
    (property "Manufacturer" "Bourns" (at 147.32 185.42 0)
      (effects (font (size 1.27 1.27) (thickness 0.15)) (justify left bottom) hide)
    )
    (property "MPN" "CR0402-FX-2492GLF" (at 147.32 182.88 0)
      (effects (font (size 1.27 1.27) (thickness 0.15)) (justify left bottom) hide)
    )
    (property "Val" "24k9" (at 127 161.29 0)
      (effects (font (size 1.27 1.27) (thickness 0.15)) (justify left bottom))
    )
    (property "License" "Apache-2.0" (at 147.32 187.96 0)
      (effects (font (size 1.27 1.27) (thickness 0.15)) (justify left bottom) hide)
    )
    (property "Author" "Antmicro" (at 147.32 190.5 0)
      (effects (font (size 1.27 1.27) (thickness 0.15)) (justify left bottom) hide)
    )
    (property "Tolerance" "1%" (at 147.32 172.72 0)
      (effects (font (size 1.27 1.27)) (justify left bottom) hide)
    )
    (pin "1")
    (pin "2")
    (instances
      (project "scalenode-cm4-baseboard"
        (path ""
          (reference "R24") (unit 1)
        )
      )
    )
  )

  (symbol (lib_id "scalenode-cm4-baseboard:TP_0.75mm_SMD") (at 139.7 250.19 0) (unit 1)
    (in_bom yes) (on_board yes) (dnp no)
    (property "Reference" "TP9" (at 143.51 250.19 0)
      (effects (font (size 1.27 1.27) (thickness 0.15)) (justify left bottom))
    )
    (property "Value" "TP_0.75mm_SMD" (at 157.48 257.81 0)
      (effects (font (size 1.27 1.27) (thickness 0.15)) (justify left bottom) hide)
    )
    (property "Footprint" "scalenode-cm4-baseboard-footprints:TP_SMD_0.75mm" (at 157.48 260.35 0)
      (effects (font (size 1.27 1.27) (thickness 0.15)) (justify left bottom) hide)
    )
    (property "Datasheet" "" (at 157.48 262.89 0)
      (effects (font (size 1.27 1.27) (thickness 0.15)) (justify left bottom) hide)
    )
    (property "Author" "Antmicro" (at 157.48 270.51 0)
      (effects (font (size 1.27 1.27) (thickness 0.15)) (justify left bottom) hide)
    )
    (property "License" "Apache-2.0" (at 157.48 273.05 0)
      (effects (font (size 1.27 1.27) (thickness 0.15)) (justify left bottom) hide)
    )
    (property "MPN" "" (at 157.48 265.43 0)
      (effects (font (size 1.27 1.27) (thickness 0.15)) (justify left bottom) hide)
    )
    (property "Manufacturer" "" (at 157.48 267.97 0)
      (effects (font (size 1.27 1.27) (thickness 0.15)) (justify left bottom) hide)
    )
    (pin "1")
    (instances
      (project "scalenode-cm4-baseboard"
        (path ""
          (reference "TP9") (unit 1)
        )
      )
    )
  )

  (symbol (lib_id "scalenode-cm4-baseboard:C_1n_1210_2kV") (at 173.99 125.73 90) (mirror x) (unit 1)
    (in_bom yes) (on_board yes) (dnp no)
    (property "Reference" "C31" (at 176.53 128.27 90)
      (effects (font (size 1.27 1.27) (thickness 0.15)) (justify right bottom))
    )
    (property "Value" "C_1n_1210_2kV" (at 184.15 146.05 0)
      (effects (font (size 1.27 1.27) (thickness 0.15)) (justify left bottom) hide)
    )
    (property "Footprint" "scalenode-cm4-baseboard-footprints:C_1210_3225Metric" (at 186.69 146.05 0)
      (effects (font (size 1.27 1.27) (thickness 0.15)) (justify left bottom) hide)
    )
    (property "Datasheet" "https://www.kemet.com/en/us/capacitors/product/C1210C102KGRACTU.html" (at 189.23 146.05 0)
      (effects (font (size 1.27 1.27) (thickness 0.15)) (justify left bottom) hide)
    )
    (property "Manufacturer" "KEMET" (at 194.31 146.05 0)
      (effects (font (size 1.27 1.27) (thickness 0.15)) (justify left bottom) hide)
    )
    (property "MPN" "C1210C102KGRACTU" (at 191.77 146.05 0)
      (effects (font (size 1.27 1.27) (thickness 0.15)) (justify left bottom) hide)
    )
    (property "Val" "1n" (at 176.53 128.27 90)
      (effects (font (size 1.27 1.27) (thickness 0.15)) (justify right top))
    )
    (property "License" "Apache-2.0" (at 196.85 146.05 0)
      (effects (font (size 1.27 1.27) (thickness 0.15)) (justify left bottom) hide)
    )
    (property "Author" "Antmicro" (at 199.39 146.05 0)
      (effects (font (size 1.27 1.27) (thickness 0.15)) (justify left bottom) hide)
    )
    (property "Voltage" "2kV" (at 201.93 146.05 0)
      (effects (font (size 1.27 1.27)) (justify left bottom) hide)
    )
    (property "Dielectric" "" (at 204.47 146.05 0)
      (effects (font (size 1.27 1.27)) (justify left bottom) hide)
    )
    (pin "1")
    (pin "2")
    (instances
      (project "scalenode-cm4-baseboard"
        (path ""
          (reference "C31") (unit 1)
        )
      )
    )
  )

  (symbol (lib_id "scalenode-cm4-baseboard:C_47u_0603") (at 314.96 196.85 90) (unit 1)
    (in_bom yes) (on_board yes) (dnp no)
    (property "Reference" "C36" (at 314.96 191.77 90)
      (effects (font (size 1.27 1.27) (thickness 0.15)) (justify left bottom))
    )
    (property "Value" "C_47u_0603" (at 325.12 176.53 0)
      (effects (font (size 1.27 1.27) (thickness 0.15)) (justify left bottom) hide)
    )
    (property "Footprint" "scalenode-cm4-baseboard-footprints:C_0603_1608Metric" (at 327.66 176.53 0)
      (effects (font (size 1.27 1.27) (thickness 0.15)) (justify left bottom) hide)
    )
    (property "Datasheet" "https://www.murata.com/products/productdetail?partno=GRM188R60J476ME15%23" (at 330.2 176.53 0)
      (effects (font (size 1.27 1.27) (thickness 0.15)) (justify left bottom) hide)
    )
    (property "Manufacturer" "Murata" (at 335.28 176.53 0)
      (effects (font (size 1.27 1.27) (thickness 0.15)) (justify left bottom) hide)
    )
    (property "MPN" "GRM188R60J476ME15D" (at 332.74 176.53 0)
      (effects (font (size 1.27 1.27) (thickness 0.15)) (justify left bottom) hide)
    )
    (property "Val" "47u" (at 314.96 195.58 90)
      (effects (font (size 1.27 1.27) (thickness 0.15)) (justify left bottom))
    )
    (property "License" "Apache-2.0" (at 337.82 176.53 0)
      (effects (font (size 1.27 1.27) (thickness 0.15)) (justify left bottom) hide)
    )
    (property "Author" "Antmicro" (at 340.36 176.53 0)
      (effects (font (size 1.27 1.27) (thickness 0.15)) (justify left bottom) hide)
    )
    (property "Voltage" "" (at 342.9 176.53 0)
      (effects (font (size 1.27 1.27)) (justify left bottom) hide)
    )
    (property "Dielectric" "" (at 345.44 176.53 0)
      (effects (font (size 1.27 1.27)) (justify left bottom) hide)
    )
    (pin "1")
    (pin "2")
    (instances
      (project "scalenode-cm4-baseboard"
        (path ""
          (reference "C36") (unit 1)
        )
      )
    )
  )

  (symbol (lib_id "scalenode-cm4-baseboard:R_75R_0402") (at 163.83 114.3 270) (unit 1)
    (in_bom yes) (on_board yes) (dnp no)
    (property "Reference" "R25" (at 158.75 114.3 90)
      (effects (font (size 1.27 1.27) (thickness 0.15)) (justify left bottom))
    )
    (property "Value" "R_75R_0402" (at 151.13 134.62 0)
      (effects (font (size 1.27 1.27) (thickness 0.15)) (justify left bottom) hide)
    )
    (property "Footprint" "scalenode-cm4-baseboard-footprints:R_0402_1005Metric" (at 148.59 134.62 0)
      (effects (font (size 1.27 1.27) (thickness 0.15)) (justify left bottom) hide)
    )
    (property "Datasheet" "https://www.bourns.com/docs/product-datasheets/cr.pdf" (at 146.05 134.62 0)
      (effects (font (size 1.27 1.27) (thickness 0.15)) (justify left bottom) hide)
    )
    (property "Manufacturer" "Bourns" (at 140.97 134.62 0)
      (effects (font (size 1.27 1.27) (thickness 0.15)) (justify left bottom) hide)
    )
    (property "MPN" "CR0402-FX-75R0GLF" (at 143.51 134.62 0)
      (effects (font (size 1.27 1.27) (thickness 0.15)) (justify left bottom) hide)
    )
    (property "Val" "75R" (at 158.75 120.65 90)
      (effects (font (size 1.27 1.27) (thickness 0.15)) (justify left bottom))
    )
    (property "License" "Apache-2.0" (at 138.43 134.62 0)
      (effects (font (size 1.27 1.27) (thickness 0.15)) (justify left bottom) hide)
    )
    (property "Author" "Antmicro" (at 135.89 134.62 0)
      (effects (font (size 1.27 1.27) (thickness 0.15)) (justify left bottom) hide)
    )
    (property "Tolerance" "1%" (at 153.67 134.62 0)
      (effects (font (size 1.27 1.27)) (justify left bottom) hide)
    )
    (pin "1")
    (pin "2")
    (instances
      (project "scalenode-cm4-baseboard"
        (path ""
          (reference "R25") (unit 1)
        )
      )
    )
  )

  (symbol (lib_id "scalenode-cm4-baseboard:TPS2378DDA") (at 138.43 160.02 0) (unit 1)
    (in_bom yes) (on_board yes) (dnp no)
    (property "Reference" "U8" (at 142.24 153.67 0)
      (effects (font (size 1.27 1.27) (thickness 0.15)) (justify left bottom))
    )
    (property "Value" "TPS2378DDA" (at 173.99 162.56 0)
      (effects (font (size 1.27 1.27) (thickness 0.15)) (justify left bottom) hide)
    )
    (property "Footprint" "scalenode-cm4-baseboard-footprints:SOIC-8-1EP_3.9x4.9x1.75mm_P1.27mm" (at 173.99 165.1 0)
      (effects (font (size 1.27 1.27) (thickness 0.15)) (justify left bottom) hide)
    )
    (property "Datasheet" "http://www.ti.com/lit/ds/symlink/tps2378.pdf" (at 173.99 167.64 0)
      (effects (font (size 1.27 1.27) (thickness 0.15)) (justify left bottom) hide)
    )
    (property "Manufacturer" "Texas Instruments" (at 173.99 170.18 0)
      (effects (font (size 1.27 1.27) (thickness 0.15)) (justify left bottom) hide)
    )
    (property "MPN" "TPS2378DDA" (at 142.24 156.21 0)
      (effects (font (size 1.27 1.27) (thickness 0.15)) (justify left bottom))
    )
    (property "Author" "Antmicro" (at 173.99 175.26 0)
      (effects (font (size 1.27 1.27) (thickness 0.15)) (justify left bottom) hide)
    )
    (property "License" "Apache-2.0" (at 173.99 177.8 0)
      (effects (font (size 1.27 1.27) (thickness 0.15)) (justify left bottom) hide)
    )
    (pin "1")
    (pin "2")
    (pin "3")
    (pin "4")
    (pin "5")
    (pin "6")
    (pin "7")
    (pin "8")
    (pin "9")
    (instances
      (project "scalenode-cm4-baseboard"
        (path ""
          (reference "U8") (unit 1)
        )
      )
    )
  )

  (symbol (lib_id "scalenode-cm4-baseboard:GND") (at 345.44 204.47 0) (unit 1)
    (in_bom yes) (on_board yes) (dnp no) (fields_autoplaced)
    (property "Reference" "#PWR021" (at 354.33 207.01 0)
      (effects (font (size 1.27 1.27) (thickness 0.15)) (justify left bottom) hide)
    )
    (property "Value" "GND" (at 343.4298 209.55 0)
      (effects (font (size 1.27 1.27) (thickness 0.15)) (justify left bottom))
    )
    (property "Footprint" "" (at 354.33 212.09 0)
      (effects (font (size 1.27 1.27) (thickness 0.15)) (justify left bottom) hide)
    )
    (property "Datasheet" "" (at 354.33 217.17 0)
      (effects (font (size 1.27 1.27) (thickness 0.15)) (justify left bottom) hide)
    )
    (property "Author" "Antmicro" (at 354.33 212.09 0)
      (effects (font (size 1.27 1.27) (thickness 0.15)) (justify left bottom) hide)
    )
    (property "License" "Apache-2.0" (at 354.33 214.63 0)
      (effects (font (size 1.27 1.27) (thickness 0.15)) (justify left bottom) hide)
    )
    (pin "1")
    (instances
      (project "scalenode-cm4-baseboard"
        (path ""
          (reference "#PWR021") (unit 1)
        )
      )
    )
  )

  (symbol (lib_id "scalenode-cm4-baseboard:TPS2373-3RGW") (at 105.41 218.44 0) (unit 1)
    (in_bom no) (on_board yes) (dnp yes)
    (property "Reference" "U3" (at 107.95 212.725 0)
      (effects (font (size 1.27 1.27) (thickness 0.15)) (justify left bottom))
    )
    (property "Value" "TPS2373-3RGW" (at 151.13 231.14 0)
      (effects (font (size 1.27 1.27) (thickness 0.15)) (justify left bottom) hide)
    )
    (property "Footprint" "scalenode-cm4-baseboard-footprints:VQFN-20_5x5x1mm_P0.65mm" (at 151.13 226.06 0)
      (effects (font (size 1.27 1.27) (thickness 0.15)) (justify left bottom) hide)
    )
    (property "Datasheet" "https://www.ti.com/lit/ds/symlink/tps2373.pdf?ts=1659968389615&ref_url=https%253A%252F%252Fwww.ti.com%252Fpower-management%252Fpower-over-ethernet-poe%252Fpowered-devices%252Fproducts.html" (at 151.13 228.6 0)
      (effects (font (size 1.27 1.27) (thickness 0.15)) (justify left bottom) hide)
    )
    (property "MPN" "TPS2373-3RGWR" (at 107.95 215.265 0)
      (effects (font (size 1.27 1.27) (thickness 0.15)) (justify left bottom))
    )
    (property "Manufacturer" "Texas Instruments" (at 151.13 233.68 0)
      (effects (font (size 1.27 1.27) (thickness 0.15)) (justify left bottom) hide)
    )
    (property "Author" "Antmicro" (at 151.13 236.22 0)
      (effects (font (size 1.27 1.27) (thickness 0.15)) (justify left bottom) hide)
    )
    (property "License" "Apache-2.0" (at 151.13 238.76 0)
      (effects (font (size 1.27 1.27) (thickness 0.15)) (justify left bottom) hide)
    )
    (property "DNP" "DNP" (at 120.015 233.045 0)
      (effects (font (size 1 1)))
    )
    (pin "1")
    (pin "10")
    (pin "11")
    (pin "12")
    (pin "13")
    (pin "14")
    (pin "15")
    (pin "16")
    (pin "17")
    (pin "18")
    (pin "19")
    (pin "2")
    (pin "21")
    (pin "3")
    (pin "4")
    (pin "5")
    (pin "6")
    (pin "7")
    (pin "8")
    (pin "9")
    (instances
      (project "scalenode-cm4-baseboard"
        (path ""
          (reference "U3") (unit 1)
        )
      )
    )
  )

  (symbol (lib_id "scalenode-cm4-baseboard:PTC_4.5A_1206") (at 335.28 185.42 0) (unit 1)
    (in_bom yes) (on_board yes) (dnp no)
    (property "Reference" "F1" (at 337.82 180.34 0)
      (effects (font (size 1.27 1.27)))
    )
    (property "Value" "PTC_4.5A_1206" (at 349.25 187.96 0)
      (effects (font (size 1.27 1.27) (thickness 0.15)) (justify left bottom) hide)
    )
    (property "Footprint" "scalenode-cm4-baseboard-footprints:F_1206_3216Metric" (at 349.25 190.5 0)
      (effects (font (size 1.27 1.27) (thickness 0.15)) (justify left bottom) hide)
    )
    (property "Datasheet" "http://www.farnell.com/datasheets/2282556.pdf" (at 349.25 193.04 0)
      (effects (font (size 1.27 1.27) (thickness 0.15)) (justify left bottom) hide)
    )
    (property "MPN" "1206L450SLWR" (at 330.2 184.15 0)
      (effects (font (size 1.27 1.27) (thickness 0.15)) (justify left bottom))
    )
    (property "Manufacturer" "Littelfuse" (at 349.25 198.12 0)
      (effects (font (size 1.27 1.27) (thickness 0.15)) (justify left bottom) hide)
    )
    (property "Author" "Antmicro" (at 349.25 200.66 0)
      (effects (font (size 1.27 1.27) (thickness 0.15)) (justify left bottom) hide)
    )
    (property "License" "Apache-2.0" (at 349.25 203.2 0)
      (effects (font (size 1.27 1.27) (thickness 0.15)) (justify left bottom) hide)
    )
    (pin "1")
    (pin "2")
    (instances
      (project "scalenode-cm4-baseboard"
        (path ""
          (reference "F1") (unit 1)
        )
      )
    )
  )

  (symbol (lib_id "scalenode-cm4-baseboard:C_47u_0603") (at 308.61 196.85 90) (unit 1)
    (in_bom yes) (on_board yes) (dnp no)
    (property "Reference" "C35" (at 308.61 191.77 90)
      (effects (font (size 1.27 1.27) (thickness 0.15)) (justify left bottom))
    )
    (property "Value" "C_47u_0603" (at 318.77 176.53 0)
      (effects (font (size 1.27 1.27) (thickness 0.15)) (justify left bottom) hide)
    )
    (property "Footprint" "scalenode-cm4-baseboard-footprints:C_0603_1608Metric" (at 321.31 176.53 0)
      (effects (font (size 1.27 1.27) (thickness 0.15)) (justify left bottom) hide)
    )
    (property "Datasheet" "https://www.murata.com/products/productdetail?partno=GRM188R60J476ME15%23" (at 323.85 176.53 0)
      (effects (font (size 1.27 1.27) (thickness 0.15)) (justify left bottom) hide)
    )
    (property "Manufacturer" "Murata" (at 328.93 176.53 0)
      (effects (font (size 1.27 1.27) (thickness 0.15)) (justify left bottom) hide)
    )
    (property "MPN" "GRM188R60J476ME15D" (at 326.39 176.53 0)
      (effects (font (size 1.27 1.27) (thickness 0.15)) (justify left bottom) hide)
    )
    (property "Val" "47u" (at 308.61 195.58 90)
      (effects (font (size 1.27 1.27) (thickness 0.15)) (justify left bottom))
    )
    (property "License" "Apache-2.0" (at 331.47 176.53 0)
      (effects (font (size 1.27 1.27) (thickness 0.15)) (justify left bottom) hide)
    )
    (property "Author" "Antmicro" (at 334.01 176.53 0)
      (effects (font (size 1.27 1.27) (thickness 0.15)) (justify left bottom) hide)
    )
    (property "Voltage" "" (at 336.55 176.53 0)
      (effects (font (size 1.27 1.27)) (justify left bottom) hide)
    )
    (property "Dielectric" "" (at 339.09 176.53 0)
      (effects (font (size 1.27 1.27)) (justify left bottom) hide)
    )
    (pin "1")
    (pin "2")
    (instances
      (project "scalenode-cm4-baseboard"
        (path ""
          (reference "C35") (unit 1)
        )
      )
    )
  )

  (symbol (lib_id "scalenode-cm4-baseboard:R_10k_0402") (at 157.48 215.9 90) (unit 1)
    (in_bom no) (on_board yes) (dnp yes)
    (property "Reference" "R41" (at 162.56 210.82 90)
      (effects (font (size 1.27 1.27) (thickness 0.15)) (justify left bottom))
    )
    (property "Value" "R_10k_0402" (at 170.18 195.58 0)
      (effects (font (size 1.27 1.27) (thickness 0.15)) (justify left bottom) hide)
    )
    (property "Footprint" "scalenode-cm4-baseboard-footprints:R_0402_1005Metric" (at 172.72 195.58 0)
      (effects (font (size 1.27 1.27) (thickness 0.15)) (justify left bottom) hide)
    )
    (property "Datasheet" "https://www.bourns.com/docs/product-datasheets/cr.pdf" (at 175.26 195.58 0)
      (effects (font (size 1.27 1.27) (thickness 0.15)) (justify left bottom) hide)
    )
    (property "Manufacturer" "Bourns" (at 180.34 195.58 0)
      (effects (font (size 1.27 1.27) (thickness 0.15)) (justify left bottom) hide)
    )
    (property "MPN" "CR0402-FX-1002GLF" (at 177.8 195.58 0)
      (effects (font (size 1.27 1.27) (thickness 0.15)) (justify left bottom) hide)
    )
    (property "Val" "10k" (at 162.56 213.36 90)
      (effects (font (size 1.27 1.27) (thickness 0.15)) (justify left bottom))
    )
    (property "DNP" "DNP" (at 157.48 213.36 0)
      (effects (font (size 1 1)))
    )
    (property "License" "Apache-2.0" (at 182.88 195.58 0)
      (effects (font (size 1.27 1.27) (thickness 0.15)) (justify left bottom) hide)
    )
    (property "Author" "Antmicro" (at 185.42 195.58 0)
      (effects (font (size 1.27 1.27) (thickness 0.15)) (justify left bottom) hide)
    )
    (property "Tolerance" "1%" (at 167.64 195.58 0)
      (effects (font (size 1.27 1.27)) (justify left bottom) hide)
    )
    (pin "1")
    (pin "2")
    (instances
      (project "scalenode-cm4-baseboard"
        (path ""
          (reference "R41") (unit 1)
        )
      )
    )
  )

  (symbol (lib_id "scalenode-cm4-baseboard:FB_220Z_2A_Murata-BLM21PG_0805") (at 88.9 180.34 0) (unit 1)
    (in_bom yes) (on_board yes) (dnp no) (fields_autoplaced)
    (property "Reference" "FB1" (at 91.4019 172.72 0)
      (effects (font (size 1.524 1.524)))
    )
    (property "Value" "FB_220Z_2A_Murata-BLM21PG_0805" (at 82.7091 176.53 0)
      (effects (font (size 1.27 1.27) (thickness 0.15)) (justify left bottom))
    )
    (property "Footprint" "scalenode-cm4-baseboard-footprints:FB_0805_2012Metric" (at 102.87 185.42 0)
      (effects (font (size 1.27 1.27) (thickness 0.15)) (justify left bottom) hide)
    )
    (property "Datasheet" "https://www.murata.com/products/productdata/8796738977822/ENFA0005.pdf?1653276712000" (at 102.87 187.96 0)
      (effects (font (size 1.27 1.27) (thickness 0.15)) (justify left bottom) hide)
    )
    (property "MPN" "BLM21PG221SN1D" (at 102.87 190.5 0)
      (effects (font (size 1.27 1.27) (thickness 0.15)) (justify left bottom) hide)
    )
    (property "Manufacturer" "Murata" (at 102.87 193.04 0)
      (effects (font (size 1.27 1.27) (thickness 0.15)) (justify left bottom) hide)
    )
    (property "Author" "Antmicro" (at 102.87 195.58 0)
      (effects (font (size 1.27 1.27) (thickness 0.15)) (justify left bottom) hide)
    )
    (property "License" "Apache-2.0" (at 102.87 198.12 0)
      (effects (font (size 1.27 1.27) (thickness 0.15)) (justify left bottom) hide)
    )
    (pin "1")
    (pin "2")
    (instances
      (project "scalenode-cm4-baseboard"
        (path ""
          (reference "FB1") (unit 1)
        )
      )
    )
  )

  (symbol (lib_id "scalenode-cm4-baseboard:SMAJ6.5A") (at 328.93 196.85 90) (unit 1)
    (in_bom yes) (on_board yes) (dnp no)
    (property "Reference" "D8" (at 332.74 191.77 90)
      (effects (font (size 1.27 1.27) (thickness 0.15)) (justify right bottom))
    )
    (property "Value" "SMAJ6.5A" (at 341.63 193.9924 90)
      (effects (font (size 1.27 1.27) (thickness 0.15)) (justify left bottom))
    )
    (property "Footprint" "scalenode-cm4-baseboard-footprints:DO-214AC" (at 339.09 175.26 0)
      (effects (font (size 1.27 1.27) (thickness 0.15)) (justify left bottom) hide)
    )
    (property "Datasheet" "http://www.farnell.com/datasheets/2794252.pdf" (at 341.63 175.26 0)
      (effects (font (size 1.27 1.27) (thickness 0.15)) (justify left bottom) hide)
    )
    (property "MPN" "SMAJ6.5A" (at 344.17 175.26 0)
      (effects (font (size 1.27 1.27) (thickness 0.15)) (justify left bottom) hide)
    )
    (property "Manufacturer" "YAGEO" (at 346.71 175.26 0)
      (effects (font (size 1.27 1.27) (thickness 0.15)) (justify left bottom) hide)
    )
    (property "Author" "Antmicro" (at 349.25 175.26 0)
      (effects (font (size 1.27 1.27) (thickness 0.15)) (justify left bottom) hide)
    )
    (property "License" "Apache-2.0" (at 351.79 175.26 0)
      (effects (font (size 1.27 1.27) (thickness 0.15)) (justify left bottom) hide)
    )
    (pin "A")
    (pin "K")
    (instances
      (project "scalenode-cm4-baseboard"
        (path ""
          (reference "D8") (unit 1)
        )
      )
    )
  )

  (symbol (lib_id "scalenode-cm4-baseboard:JST_XH_1x2_B2B-XH-A-LF-SN") (at 308.61 64.77 0) (mirror y) (unit 1)
    (in_bom yes) (on_board yes) (dnp no)
    (property "Reference" "J1" (at 304.8 58.42 0)
      (effects (font (size 1.27 1.27) (thickness 0.15)) (justify bottom))
    )
    (property "Value" "JST_XH_1x2_B2B-XH-A-LF-SN" (at 319.405 60.96 0)
      (effects (font (size 1.27 1.27) (thickness 0.15)) (justify left bottom))
    )
    (property "Footprint" "scalenode-cm4-baseboard-footprints:Conn_JST_XH_1x2_B2B-XH-A-LF-SN" (at 300.99 68.58 0)
      (effects (font (size 1.27 1.27) (thickness 0.15)) (justify left bottom) hide)
    )
    (property "Datasheet" "http://www.jst-mfg.com/product/pdf/eng/eXH.pdf" (at 300.99 71.12 0)
      (effects (font (size 1.27 1.27) (thickness 0.15)) (justify left bottom) hide)
    )
    (property "MPN" "B2B-XH-A(LF)(SN)" (at 300.99 73.66 0)
      (effects (font (size 1.27 1.27) (thickness 0.15)) (justify left bottom) hide)
    )
    (property "Manufacturer" "JST Automotive Connectors" (at 300.99 76.2 0)
      (effects (font (size 1.27 1.27) (thickness 0.15)) (justify left bottom) hide)
    )
    (property "Author" "Antmicro" (at 300.99 78.74 0)
      (effects (font (size 1.27 1.27) (thickness 0.15)) (justify left bottom) hide)
    )
    (property "License" "Apache-2.0" (at 300.99 81.28 0)
      (effects (font (size 1.27 1.27) (thickness 0.15)) (justify left bottom) hide)
    )
    (pin "1")
    (pin "2")
    (instances
      (project "scalenode-cm4-baseboard"
        (path ""
          (reference "J1") (unit 1)
        )
      )
    )
  )

  (symbol (lib_id "scalenode-cm4-baseboard:PWR_FLAG") (at 73.66 85.09 0) (unit 1)
    (in_bom yes) (on_board yes) (dnp no) (fields_autoplaced)
    (property "Reference" "#FLG0106" (at 73.66 83.185 0)
      (effects (font (size 1.27 1.27)) hide)
    )
    (property "Value" "PWR_FLAG" (at 81.28 83.8199 0)
      (effects (font (size 1.27 1.27)))
    )
    (property "Footprint" "" (at 73.66 85.09 0)
      (effects (font (size 1.27 1.27)) hide)
    )
    (property "Datasheet" "" (at 73.66 85.09 0)
      (effects (font (size 1.27 1.27)) hide)
    )
    (pin "1")
    (instances
      (project "scalenode-cm4-baseboard"
        (path ""
          (reference "#FLG0106") (unit 1)
        )
      )
    )
  )

  (symbol (lib_id "scalenode-cm4-baseboard:URB4805YMD-30WR3") (at 279.4 218.44 0) (unit 1)
    (in_bom no) (on_board yes) (dnp yes)
    (property "Reference" "U4" (at 284.48 210.82 0)
      (effects (font (size 1.27 1.27) (thickness 0.15)) (justify left bottom))
    )
    (property "Value" "URB4805YMD-30WR3" (at 314.96 226.06 0)
      (effects (font (size 1.27 1.27) (thickness 0.15)) (justify left bottom) hide)
    )
    (property "Footprint" "scalenode-cm4-baseboard-footprints:URB4805YMD-30WR3" (at 314.96 228.6 0)
      (effects (font (size 1.27 1.27) (thickness 0.15)) (justify left bottom) hide)
    )
    (property "Datasheet" "https://www.mornsun-power.com/html/pdf/URB4805YMD-30WR3.html" (at 314.96 231.14 0)
      (effects (font (size 1.27 1.27) (thickness 0.15)) (justify left bottom) hide)
    )
    (property "Manufacturer" "Mornsun" (at 314.96 233.68 0)
      (effects (font (size 1.27 1.27) (thickness 0.15)) (justify left bottom) hide)
    )
    (property "MPN" "URB4805YMD-30WR3" (at 279.4 213.36 0)
      (effects (font (size 1.27 1.27) (thickness 0.15)) (justify left bottom))
    )
    (property "License" "Apache-2.0" (at 314.96 238.76 0)
      (effects (font (size 1.27 1.27) (thickness 0.15)) (justify left bottom) hide)
    )
    (property "DNP" "DNP" (at 279.4 210.82 0)
      (effects (font (size 1.27 1.27)) (justify left bottom))
    )
    (property "Author" "Antmicro" (at 314.96 236.22 0)
      (effects (font (size 1.27 1.27) (thickness 0.15)) (justify left bottom) hide)
    )
    (pin "1")
    (pin "2")
    (pin "3")
    (pin "4")
    (pin "5")
    (pin "6")
    (instances
      (project "scalenode-cm4-baseboard"
        (path ""
          (reference "U4") (unit 1)
        )
      )
    )
  )

  (symbol (lib_id "scalenode-cm4-baseboard:C_100n_100V_0805") (at 118.11 162.56 90) (unit 1)
    (in_bom yes) (on_board yes) (dnp no)
    (property "Reference" "C20" (at 121.92 156.21 90)
      (effects (font (size 1.27 1.27) (thickness 0.15)) (justify left bottom))
    )
    (property "Value" "C_100n_100V_0805" (at 128.27 142.24 0)
      (effects (font (size 1.27 1.27) (thickness 0.15)) (justify left bottom) hide)
    )
    (property "Footprint" "scalenode-cm4-baseboard-footprints:C_0805_2012Metric" (at 130.81 142.24 0)
      (effects (font (size 1.27 1.27) (thickness 0.15)) (justify left bottom) hide)
    )
    (property "Datasheet" "https://product.samsungsem.com/mlcc/CL21B104KCFNNN.do" (at 133.35 142.24 0)
      (effects (font (size 1.27 1.27) (thickness 0.15)) (justify left bottom) hide)
    )
    (property "Manufacturer" "Samsung Electro-Mechanics" (at 138.43 142.24 0)
      (effects (font (size 1.27 1.27) (thickness 0.15)) (justify left bottom) hide)
    )
    (property "MPN" "CL21B104KCFNNNE" (at 135.89 142.24 0)
      (effects (font (size 1.27 1.27) (thickness 0.15)) (justify left bottom) hide)
    )
    (property "Val" "100n" (at 123.19 162.56 90)
      (effects (font (size 1.27 1.27) (thickness 0.15)) (justify left bottom))
    )
    (property "Author" "Antmicro" (at 143.51 142.24 0)
      (effects (font (size 1.27 1.27) (thickness 0.15)) (justify left bottom) hide)
    )
    (property "License" "Apache-2.0" (at 140.97 142.24 0)
      (effects (font (size 1.27 1.27) (thickness 0.15)) (justify left bottom) hide)
    )
    (property "Voltage" "100V" (at 146.05 142.24 0)
      (effects (font (size 1.27 1.27)) (justify left bottom) hide)
    )
    (property "Dielectric" "X7R" (at 148.59 142.24 0)
      (effects (font (size 1.27 1.27)) (justify left bottom) hide)
    )
    (pin "1")
    (pin "2")
    (instances
      (project "scalenode-cm4-baseboard"
        (path ""
          (reference "C20") (unit 1)
        )
      )
    )
  )

  (symbol (lib_id "scalenode-cm4-baseboard:FB_220Z_2A_Murata-BLM21PG_0805") (at 88.9 149.86 0) (unit 1)
    (in_bom yes) (on_board yes) (dnp no) (fields_autoplaced)
    (property "Reference" "FB2" (at 91.4019 142.24 0)
      (effects (font (size 1.524 1.524)))
    )
    (property "Value" "FB_220Z_2A_Murata-BLM21PG_0805" (at 82.7091 146.05 0)
      (effects (font (size 1.27 1.27) (thickness 0.15)) (justify left bottom))
    )
    (property "Footprint" "scalenode-cm4-baseboard-footprints:FB_0805_2012Metric" (at 102.87 154.94 0)
      (effects (font (size 1.27 1.27) (thickness 0.15)) (justify left bottom) hide)
    )
    (property "Datasheet" "https://www.murata.com/products/productdata/8796738977822/ENFA0005.pdf?1653276712000" (at 102.87 157.48 0)
      (effects (font (size 1.27 1.27) (thickness 0.15)) (justify left bottom) hide)
    )
    (property "MPN" "BLM21PG221SN1D" (at 102.87 160.02 0)
      (effects (font (size 1.27 1.27) (thickness 0.15)) (justify left bottom) hide)
    )
    (property "Manufacturer" "Murata" (at 102.87 162.56 0)
      (effects (font (size 1.27 1.27) (thickness 0.15)) (justify left bottom) hide)
    )
    (property "Author" "Antmicro" (at 102.87 165.1 0)
      (effects (font (size 1.27 1.27) (thickness 0.15)) (justify left bottom) hide)
    )
    (property "License" "Apache-2.0" (at 102.87 167.64 0)
      (effects (font (size 1.27 1.27) (thickness 0.15)) (justify left bottom) hide)
    )
    (pin "1")
    (pin "2")
    (instances
      (project "scalenode-cm4-baseboard"
        (path ""
          (reference "FB2") (unit 1)
        )
      )
    )
  )

  (symbol (lib_id "scalenode-cm4-baseboard:R_32k4_0805") (at 242.57 185.42 90) (unit 1)
    (in_bom yes) (on_board yes) (dnp no)
    (property "Reference" "R33" (at 243.84 182.88 90)
      (effects (font (size 1.27 1.27) (thickness 0.15)) (justify right top))
    )
    (property "Value" "R_32k4_0805" (at 255.27 165.1 0)
      (effects (font (size 1.27 1.27) (thickness 0.15)) (justify left bottom) hide)
    )
    (property "Footprint" "scalenode-cm4-baseboard-footprints:R_0805_2012Metric" (at 257.81 165.1 0)
      (effects (font (size 1.27 1.27) (thickness 0.15)) (justify left bottom) hide)
    )
    (property "Datasheet" "https://www.bourns.com/docs/product-datasheets/cr.pdf" (at 260.35 165.1 0)
      (effects (font (size 1.27 1.27) (thickness 0.15)) (justify left bottom) hide)
    )
    (property "Manufacturer" "Bourns" (at 265.43 165.1 0)
      (effects (font (size 1.27 1.27) (thickness 0.15)) (justify left bottom) hide)
    )
    (property "MPN" "CR0805-FX-3242ELF" (at 262.89 165.1 0)
      (effects (font (size 1.27 1.27) (thickness 0.15)) (justify left bottom) hide)
    )
    (property "Val" "32k4" (at 243.84 182.88 90)
      (effects (font (size 1.27 1.27) (thickness 0.15)) (justify right bottom))
    )
    (property "License" "Apache-2.0" (at 267.97 165.1 0)
      (effects (font (size 1.27 1.27) (thickness 0.15)) (justify left bottom) hide)
    )
    (property "Author" "Antmicro" (at 270.51 165.1 0)
      (effects (font (size 1.27 1.27) (thickness 0.15)) (justify left bottom) hide)
    )
    (property "Tolerance" "1%" (at 252.73 165.1 0)
      (effects (font (size 1.27 1.27)) (justify left bottom) hide)
    )
    (pin "1")
    (pin "2")
    (instances
      (project "scalenode-cm4-baseboard"
        (path ""
          (reference "R33") (unit 1)
        )
      )
    )
  )

  (symbol (lib_id "scalenode-cm4-baseboard:C_22u_100V_2220") (at 228.6 194.31 90) (unit 1)
    (in_bom yes) (on_board yes) (dnp no)
    (property "Reference" "C29" (at 228.6 193.04 90)
      (effects (font (size 1.27 1.27) (thickness 0.15)) (justify left bottom))
    )
    (property "Value" "C_22u_100V_2220" (at 238.76 173.99 0)
      (effects (font (size 1.27 1.27) (thickness 0.15)) (justify left bottom) hide)
    )
    (property "Footprint" "scalenode-cm4-baseboard-footprints:C_2220_5650Metric" (at 241.3 173.99 0)
      (effects (font (size 1.27 1.27) (thickness 0.15)) (justify left bottom) hide)
    )
    (property "Datasheet" "https://product.tdk.com/en/search/capacitor/ceramic/mlcc/info?part_no=C5750X7S2A226M280KB" (at 243.84 173.99 0)
      (effects (font (size 1.27 1.27) (thickness 0.15)) (justify left bottom) hide)
    )
    (property "Manufacturer" "TDK" (at 248.92 173.99 0)
      (effects (font (size 1.27 1.27) (thickness 0.15)) (justify left bottom) hide)
    )
    (property "MPN" "C5750X7S2A226M280KB" (at 246.38 173.99 0)
      (effects (font (size 1.27 1.27) (thickness 0.15)) (justify left bottom) hide)
    )
    (property "Val" "22u" (at 228.6 190.5 0)
      (effects (font (size 1.27 1.27) (thickness 0.15)) (justify left bottom))
    )
    (property "Author" "Antmicro" (at 254 173.99 0)
      (effects (font (size 1.27 1.27) (thickness 0.15)) (justify left bottom) hide)
    )
    (property "License" "Apache-2.0" (at 251.46 173.99 0)
      (effects (font (size 1.27 1.27) (thickness 0.15)) (justify left bottom) hide)
    )
    (property "Voltage" "100V" (at 256.54 173.99 0)
      (effects (font (size 1.27 1.27)) (justify left bottom) hide)
    )
    (property "Dielectric" "X7S" (at 259.08 173.99 0)
      (effects (font (size 1.27 1.27)) (justify left bottom) hide)
    )
    (pin "1")
    (pin "2")
    (instances
      (project "scalenode-cm4-baseboard"
        (path ""
          (reference "C29") (unit 1)
        )
      )
    )
  )

  (symbol (lib_id "scalenode-cm4-baseboard:C_10n_0402") (at 184.15 107.95 90) (unit 1)
    (in_bom yes) (on_board yes) (dnp no)
    (property "Reference" "C34" (at 184.15 102.87 90)
      (effects (font (size 1.27 1.27) (thickness 0.15)) (justify left bottom))
    )
    (property "Value" "C_10n_0402" (at 194.31 87.63 0)
      (effects (font (size 1.27 1.27) (thickness 0.15)) (justify left bottom) hide)
    )
    (property "Footprint" "scalenode-cm4-baseboard-footprints:C_0402_1005Metric" (at 196.85 87.63 0)
      (effects (font (size 1.27 1.27) (thickness 0.15)) (justify left bottom) hide)
    )
    (property "Datasheet" "https://www.murata.com/products/productdetail?partno=GRM155R71H103KA88%23" (at 199.39 87.63 0)
      (effects (font (size 1.27 1.27) (thickness 0.15)) (justify left bottom) hide)
    )
    (property "Manufacturer" "Murata" (at 204.47 87.63 0)
      (effects (font (size 1.27 1.27) (thickness 0.15)) (justify left bottom) hide)
    )
    (property "MPN" "GRM155R71H103KA88D" (at 201.93 87.63 0)
      (effects (font (size 1.27 1.27) (thickness 0.15)) (justify left bottom) hide)
    )
    (property "Val" "10n" (at 184.15 106.68 90)
      (effects (font (size 1.27 1.27) (thickness 0.15)) (justify left bottom))
    )
    (property "License" "Apache-2.0" (at 207.01 87.63 0)
      (effects (font (size 1.27 1.27) (thickness 0.15)) (justify left bottom) hide)
    )
    (property "Author" "Antmicro" (at 209.55 87.63 0)
      (effects (font (size 1.27 1.27) (thickness 0.15)) (justify left bottom) hide)
    )
    (property "Voltage" "50V" (at 212.09 87.63 0)
      (effects (font (size 1.27 1.27)) (justify left bottom) hide)
    )
    (property "Dielectric" "X7R" (at 214.63 87.63 0)
      (effects (font (size 1.27 1.27)) (justify left bottom) hide)
    )
    (pin "1")
    (pin "2")
    (instances
      (project "scalenode-cm4-baseboard"
        (path ""
          (reference "C34") (unit 1)
        )
      )
    )
  )

  (symbol (lib_id "scalenode-cm4-baseboard:C_10n_0402") (at 177.8 107.95 90) (unit 1)
    (in_bom yes) (on_board yes) (dnp no)
    (property "Reference" "C33" (at 177.8 102.87 90)
      (effects (font (size 1.27 1.27) (thickness 0.15)) (justify left bottom))
    )
    (property "Value" "C_10n_0402" (at 187.96 87.63 0)
      (effects (font (size 1.27 1.27) (thickness 0.15)) (justify left bottom) hide)
    )
    (property "Footprint" "scalenode-cm4-baseboard-footprints:C_0402_1005Metric" (at 190.5 87.63 0)
      (effects (font (size 1.27 1.27) (thickness 0.15)) (justify left bottom) hide)
    )
    (property "Datasheet" "https://www.murata.com/products/productdetail?partno=GRM155R71H103KA88%23" (at 193.04 87.63 0)
      (effects (font (size 1.27 1.27) (thickness 0.15)) (justify left bottom) hide)
    )
    (property "Manufacturer" "Murata" (at 198.12 87.63 0)
      (effects (font (size 1.27 1.27) (thickness 0.15)) (justify left bottom) hide)
    )
    (property "MPN" "GRM155R71H103KA88D" (at 195.58 87.63 0)
      (effects (font (size 1.27 1.27) (thickness 0.15)) (justify left bottom) hide)
    )
    (property "Val" "10n" (at 177.8 106.68 90)
      (effects (font (size 1.27 1.27) (thickness 0.15)) (justify left bottom))
    )
    (property "License" "Apache-2.0" (at 200.66 87.63 0)
      (effects (font (size 1.27 1.27) (thickness 0.15)) (justify left bottom) hide)
    )
    (property "Author" "Antmicro" (at 203.2 87.63 0)
      (effects (font (size 1.27 1.27) (thickness 0.15)) (justify left bottom) hide)
    )
    (property "Voltage" "50V" (at 205.74 87.63 0)
      (effects (font (size 1.27 1.27)) (justify left bottom) hide)
    )
    (property "Dielectric" "X7R" (at 208.28 87.63 0)
      (effects (font (size 1.27 1.27)) (justify left bottom) hide)
    )
    (pin "1")
    (pin "2")
    (instances
      (project "scalenode-cm4-baseboard"
        (path ""
          (reference "C33") (unit 1)
        )
      )
    )
  )

  (symbol (lib_id "scalenode-cm4-baseboard:GNDD") (at 208.28 204.47 0) (unit 1)
    (in_bom yes) (on_board yes) (dnp no) (fields_autoplaced)
    (property "Reference" "#PWR02" (at 223.52 207.01 0)
      (effects (font (size 1.27 1.27) (thickness 0.15)) (justify left bottom) hide)
    )
    (property "Value" "GNDD" (at 205.6348 209.55 0)
      (effects (font (size 1.27 1.27) (thickness 0.15)) (justify left bottom))
    )
    (property "Footprint" "" (at 223.52 214.63 0)
      (effects (font (size 1.27 1.27) (thickness 0.15)) (justify left bottom) hide)
    )
    (property "Datasheet" "" (at 223.52 217.17 0)
      (effects (font (size 1.27 1.27) (thickness 0.15)) (justify left bottom) hide)
    )
    (property "Author" "Antmicro" (at 223.52 212.09 0)
      (effects (font (size 1.27 1.27) (thickness 0.15)) (justify left bottom) hide)
    )
    (property "License" "Apache-2.0" (at 223.52 214.63 0)
      (effects (font (size 1.27 1.27) (thickness 0.15)) (justify left bottom) hide)
    )
    (pin "1")
    (instances
      (project "scalenode-cm4-baseboard"
        (path ""
          (reference "#PWR02") (unit 1)
        )
      )
    )
  )

  (symbol (lib_id "scalenode-cm4-baseboard:PWR_FLAG") (at 132.08 180.34 180) (unit 1)
    (in_bom yes) (on_board yes) (dnp no) (fields_autoplaced)
    (property "Reference" "#FLG0105" (at 132.08 182.245 0)
      (effects (font (size 1.27 1.27)) hide)
    )
    (property "Value" "PWR_FLAG" (at 132.08 185.42 0)
      (effects (font (size 1.27 1.27)))
    )
    (property "Footprint" "" (at 132.08 180.34 0)
      (effects (font (size 1.27 1.27)) hide)
    )
    (property "Datasheet" "" (at 132.08 180.34 0)
      (effects (font (size 1.27 1.27)) hide)
    )
    (pin "1")
    (instances
      (project "scalenode-cm4-baseboard"
        (path ""
          (reference "#FLG0105") (unit 1)
        )
      )
    )
  )

  (symbol (lib_id "scalenode-cm4-baseboard:R_49k9_0402") (at 97.79 247.65 0) (unit 1)
    (in_bom no) (on_board yes) (dnp yes)
    (property "Reference" "R38" (at 95.25 247.65 0)
      (effects (font (size 1.27 1.27) (thickness 0.15)) (justify left bottom))
    )
    (property "Value" "R_49k9_0402" (at 118.11 260.35 0)
      (effects (font (size 1.27 1.27) (thickness 0.15)) (justify left bottom) hide)
    )
    (property "Footprint" "scalenode-cm4-baseboard-footprints:R_0402_1005Metric" (at 118.11 262.89 0)
      (effects (font (size 1.27 1.27) (thickness 0.15)) (justify left bottom) hide)
    )
    (property "Datasheet" "https://www.bourns.com/docs/product-datasheets/cr.pdf" (at 118.11 265.43 0)
      (effects (font (size 1.27 1.27) (thickness 0.15)) (justify left bottom) hide)
    )
    (property "Manufacturer" "Bourns" (at 118.11 270.51 0)
      (effects (font (size 1.27 1.27) (thickness 0.15)) (justify left bottom) hide)
    )
    (property "MPN" "CR0402-FX-4992GLF" (at 118.11 267.97 0)
      (effects (font (size 1.27 1.27) (thickness 0.15)) (justify left bottom) hide)
    )
    (property "Val" "49k9" (at 101.6 247.65 0)
      (effects (font (size 1.27 1.27) (thickness 0.15)) (justify left bottom))
    )
    (property "DNP" "DNP" (at 100.33 247.65 0)
      (effects (font (size 1 1)))
    )
    (property "License" "Apache-2.0" (at 118.11 273.05 0)
      (effects (font (size 1.27 1.27) (thickness 0.15)) (justify left bottom) hide)
    )
    (property "Author" "Antmicro" (at 118.11 275.59 0)
      (effects (font (size 1.27 1.27) (thickness 0.15)) (justify left bottom) hide)
    )
    (property "Tolerance" "1%" (at 118.11 257.81 0)
      (effects (font (size 1.27 1.27)) (justify left bottom) hide)
    )
    (pin "1")
    (pin "2")
    (instances
      (project "scalenode-cm4-baseboard"
        (path ""
          (reference "R38") (unit 1)
        )
      )
    )
  )

  (symbol (lib_id "scalenode-cm4-baseboard:R_75R_0402") (at 177.8 114.3 270) (unit 1)
    (in_bom yes) (on_board yes) (dnp no)
    (property "Reference" "R31" (at 173.99 114.3 90)
      (effects (font (size 1.27 1.27) (thickness 0.15)) (justify left bottom))
    )
    (property "Value" "R_75R_0402" (at 165.1 134.62 0)
      (effects (font (size 1.27 1.27) (thickness 0.15)) (justify left bottom) hide)
    )
    (property "Footprint" "scalenode-cm4-baseboard-footprints:R_0402_1005Metric" (at 162.56 134.62 0)
      (effects (font (size 1.27 1.27) (thickness 0.15)) (justify left bottom) hide)
    )
    (property "Datasheet" "https://www.bourns.com/docs/product-datasheets/cr.pdf" (at 160.02 134.62 0)
      (effects (font (size 1.27 1.27) (thickness 0.15)) (justify left bottom) hide)
    )
    (property "Manufacturer" "Bourns" (at 154.94 134.62 0)
      (effects (font (size 1.27 1.27) (thickness 0.15)) (justify left bottom) hide)
    )
    (property "MPN" "CR0402-FX-75R0GLF" (at 157.48 134.62 0)
      (effects (font (size 1.27 1.27) (thickness 0.15)) (justify left bottom) hide)
    )
    (property "Val" "75R" (at 173.99 120.65 90)
      (effects (font (size 1.27 1.27) (thickness 0.15)) (justify left bottom))
    )
    (property "License" "Apache-2.0" (at 152.4 134.62 0)
      (effects (font (size 1.27 1.27) (thickness 0.15)) (justify left bottom) hide)
    )
    (property "Author" "Antmicro" (at 149.86 134.62 0)
      (effects (font (size 1.27 1.27) (thickness 0.15)) (justify left bottom) hide)
    )
    (property "Tolerance" "1%" (at 167.64 134.62 0)
      (effects (font (size 1.27 1.27)) (justify left bottom) hide)
    )
    (pin "1")
    (pin "2")
    (instances
      (project "scalenode-cm4-baseboard"
        (path ""
          (reference "R31") (unit 1)
        )
      )
    )
  )

  (symbol (lib_id "scalenode-cm4-baseboard:R_75R_0402") (at 170.18 114.3 270) (unit 1)
    (in_bom yes) (on_board yes) (dnp no)
    (property "Reference" "R26" (at 166.37 114.3 90)
      (effects (font (size 1.27 1.27) (thickness 0.15)) (justify left bottom))
    )
    (property "Value" "R_75R_0402" (at 157.48 134.62 0)
      (effects (font (size 1.27 1.27) (thickness 0.15)) (justify left bottom) hide)
    )
    (property "Footprint" "scalenode-cm4-baseboard-footprints:R_0402_1005Metric" (at 154.94 134.62 0)
      (effects (font (size 1.27 1.27) (thickness 0.15)) (justify left bottom) hide)
    )
    (property "Datasheet" "https://www.bourns.com/docs/product-datasheets/cr.pdf" (at 152.4 134.62 0)
      (effects (font (size 1.27 1.27) (thickness 0.15)) (justify left bottom) hide)
    )
    (property "Manufacturer" "Bourns" (at 147.32 134.62 0)
      (effects (font (size 1.27 1.27) (thickness 0.15)) (justify left bottom) hide)
    )
    (property "MPN" "CR0402-FX-75R0GLF" (at 149.86 134.62 0)
      (effects (font (size 1.27 1.27) (thickness 0.15)) (justify left bottom) hide)
    )
    (property "Val" "75R" (at 166.37 120.65 90)
      (effects (font (size 1.27 1.27) (thickness 0.15)) (justify left bottom))
    )
    (property "License" "Apache-2.0" (at 144.78 134.62 0)
      (effects (font (size 1.27 1.27) (thickness 0.15)) (justify left bottom) hide)
    )
    (property "Author" "Antmicro" (at 142.24 134.62 0)
      (effects (font (size 1.27 1.27) (thickness 0.15)) (justify left bottom) hide)
    )
    (property "Tolerance" "1%" (at 160.02 134.62 0)
      (effects (font (size 1.27 1.27)) (justify left bottom) hide)
    )
    (pin "1")
    (pin "2")
    (instances
      (project "scalenode-cm4-baseboard"
        (path ""
          (reference "R26") (unit 1)
        )
      )
    )
  )

  (symbol (lib_id "scalenode-cm4-baseboard:R_75R_0402") (at 184.15 114.3 270) (unit 1)
    (in_bom yes) (on_board yes) (dnp no)
    (property "Reference" "R32" (at 180.34 114.3 90)
      (effects (font (size 1.27 1.27) (thickness 0.15)) (justify left bottom))
    )
    (property "Value" "R_75R_0402" (at 171.45 134.62 0)
      (effects (font (size 1.27 1.27) (thickness 0.15)) (justify left bottom) hide)
    )
    (property "Footprint" "scalenode-cm4-baseboard-footprints:R_0402_1005Metric" (at 168.91 134.62 0)
      (effects (font (size 1.27 1.27) (thickness 0.15)) (justify left bottom) hide)
    )
    (property "Datasheet" "https://www.bourns.com/docs/product-datasheets/cr.pdf" (at 166.37 134.62 0)
      (effects (font (size 1.27 1.27) (thickness 0.15)) (justify left bottom) hide)
    )
    (property "Manufacturer" "Bourns" (at 161.29 134.62 0)
      (effects (font (size 1.27 1.27) (thickness 0.15)) (justify left bottom) hide)
    )
    (property "MPN" "CR0402-FX-75R0GLF" (at 163.83 134.62 0)
      (effects (font (size 1.27 1.27) (thickness 0.15)) (justify left bottom) hide)
    )
    (property "Val" "75R" (at 180.34 120.65 90)
      (effects (font (size 1.27 1.27) (thickness 0.15)) (justify left bottom))
    )
    (property "License" "Apache-2.0" (at 158.75 134.62 0)
      (effects (font (size 1.27 1.27) (thickness 0.15)) (justify left bottom) hide)
    )
    (property "Author" "Antmicro" (at 156.21 134.62 0)
      (effects (font (size 1.27 1.27) (thickness 0.15)) (justify left bottom) hide)
    )
    (property "Tolerance" "1%" (at 173.99 134.62 0)
      (effects (font (size 1.27 1.27)) (justify left bottom) hide)
    )
    (pin "1")
    (pin "2")
    (instances
      (project "scalenode-cm4-baseboard"
        (path ""
          (reference "R32") (unit 1)
        )
      )
    )
  )

  (symbol (lib_id "scalenode-cm4-baseboard:PWR_FLAG") (at 132.08 149.86 0) (unit 1)
    (in_bom yes) (on_board yes) (dnp no) (fields_autoplaced)
    (property "Reference" "#FLG0103" (at 132.08 147.955 0)
      (effects (font (size 1.27 1.27)) hide)
    )
    (property "Value" "PWR_FLAG" (at 132.08 144.78 0)
      (effects (font (size 1.27 1.27)))
    )
    (property "Footprint" "" (at 132.08 149.86 0)
      (effects (font (size 1.27 1.27)) hide)
    )
    (property "Datasheet" "" (at 132.08 149.86 0)
      (effects (font (size 1.27 1.27)) hide)
    )
    (pin "1")
    (instances
      (project "scalenode-cm4-baseboard"
        (path ""
          (reference "#FLG0103") (unit 1)
        )
      )
    )
  )

  (symbol (lib_id "scalenode-cm4-baseboard:GNDD") (at 138.43 252.73 0) (unit 1)
    (in_bom yes) (on_board yes) (dnp no) (fields_autoplaced)
    (property "Reference" "#PWR015" (at 153.67 255.27 0)
      (effects (font (size 1.27 1.27) (thickness 0.15)) (justify left bottom) hide)
    )
    (property "Value" "GNDD" (at 135.7848 257.81 0)
      (effects (font (size 1.27 1.27) (thickness 0.15)) (justify left bottom))
    )
    (property "Footprint" "" (at 153.67 262.89 0)
      (effects (font (size 1.27 1.27) (thickness 0.15)) (justify left bottom) hide)
    )
    (property "Datasheet" "" (at 153.67 265.43 0)
      (effects (font (size 1.27 1.27) (thickness 0.15)) (justify left bottom) hide)
    )
    (property "Author" "Antmicro" (at 153.67 260.35 0)
      (effects (font (size 1.27 1.27) (thickness 0.15)) (justify left bottom) hide)
    )
    (property "License" "Apache-2.0" (at 153.67 262.89 0)
      (effects (font (size 1.27 1.27) (thickness 0.15)) (justify left bottom) hide)
    )
    (pin "1")
    (instances
      (project "scalenode-cm4-baseboard"
        (path ""
          (reference "#PWR015") (unit 1)
        )
      )
    )
  )

  (symbol (lib_id "scalenode-cm4-baseboard:R_10k_0402") (at 142.24 215.9 90) (unit 1)
    (in_bom no) (on_board yes) (dnp yes)
    (property "Reference" "R39" (at 147.32 210.82 90)
      (effects (font (size 1.27 1.27) (thickness 0.15)) (justify left bottom))
    )
    (property "Value" "R_10k_0402" (at 154.94 195.58 0)
      (effects (font (size 1.27 1.27) (thickness 0.15)) (justify left bottom) hide)
    )
    (property "Footprint" "scalenode-cm4-baseboard-footprints:R_0402_1005Metric" (at 157.48 195.58 0)
      (effects (font (size 1.27 1.27) (thickness 0.15)) (justify left bottom) hide)
    )
    (property "Datasheet" "https://www.bourns.com/docs/product-datasheets/cr.pdf" (at 160.02 195.58 0)
      (effects (font (size 1.27 1.27) (thickness 0.15)) (justify left bottom) hide)
    )
    (property "Manufacturer" "Bourns" (at 165.1 195.58 0)
      (effects (font (size 1.27 1.27) (thickness 0.15)) (justify left bottom) hide)
    )
    (property "MPN" "CR0402-FX-1002GLF" (at 162.56 195.58 0)
      (effects (font (size 1.27 1.27) (thickness 0.15)) (justify left bottom) hide)
    )
    (property "Val" "10k" (at 147.32 213.36 90)
      (effects (font (size 1.27 1.27) (thickness 0.15)) (justify left bottom))
    )
    (property "DNP" "DNP" (at 142.24 213.36 0)
      (effects (font (size 1 1)))
    )
    (property "License" "Apache-2.0" (at 167.64 195.58 0)
      (effects (font (size 1.27 1.27) (thickness 0.15)) (justify left bottom) hide)
    )
    (property "Author" "Antmicro" (at 170.18 195.58 0)
      (effects (font (size 1.27 1.27) (thickness 0.15)) (justify left bottom) hide)
    )
    (property "Tolerance" "1%" (at 152.4 195.58 0)
      (effects (font (size 1.27 1.27)) (justify left bottom) hide)
    )
    (pin "1")
    (pin "2")
    (instances
      (project "scalenode-cm4-baseboard"
        (path ""
          (reference "R39") (unit 1)
        )
      )
    )
  )

  (symbol (lib_id "scalenode-cm4-baseboard:C_22u_100V_2220") (at 215.9 194.31 90) (unit 1)
    (in_bom yes) (on_board yes) (dnp no)
    (property "Reference" "C26" (at 215.9 193.04 90)
      (effects (font (size 1.27 1.27) (thickness 0.15)) (justify left bottom))
    )
    (property "Value" "C_22u_100V_2220" (at 226.06 173.99 0)
      (effects (font (size 1.27 1.27) (thickness 0.15)) (justify left bottom) hide)
    )
    (property "Footprint" "scalenode-cm4-baseboard-footprints:C_2220_5650Metric" (at 228.6 173.99 0)
      (effects (font (size 1.27 1.27) (thickness 0.15)) (justify left bottom) hide)
    )
    (property "Datasheet" "https://product.tdk.com/en/search/capacitor/ceramic/mlcc/info?part_no=C5750X7S2A226M280KB" (at 231.14 173.99 0)
      (effects (font (size 1.27 1.27) (thickness 0.15)) (justify left bottom) hide)
    )
    (property "Manufacturer" "TDK" (at 236.22 173.99 0)
      (effects (font (size 1.27 1.27) (thickness 0.15)) (justify left bottom) hide)
    )
    (property "MPN" "C5750X7S2A226M280KB" (at 233.68 173.99 0)
      (effects (font (size 1.27 1.27) (thickness 0.15)) (justify left bottom) hide)
    )
    (property "Val" "22u" (at 215.9 190.5 0)
      (effects (font (size 1.27 1.27) (thickness 0.15)) (justify left bottom))
    )
    (property "Author" "Antmicro" (at 241.3 173.99 0)
      (effects (font (size 1.27 1.27) (thickness 0.15)) (justify left bottom) hide)
    )
    (property "License" "Apache-2.0" (at 238.76 173.99 0)
      (effects (font (size 1.27 1.27) (thickness 0.15)) (justify left bottom) hide)
    )
    (property "Voltage" "100V" (at 243.84 173.99 0)
      (effects (font (size 1.27 1.27)) (justify left bottom) hide)
    )
    (property "Dielectric" "X7S" (at 246.38 173.99 0)
      (effects (font (size 1.27 1.27)) (justify left bottom) hide)
    )
    (pin "1")
    (pin "2")
    (instances
      (project "scalenode-cm4-baseboard"
        (path ""
          (reference "C26") (unit 1)
        )
      )
    )
  )

  (symbol (lib_id "scalenode-cm4-baseboard:GND") (at 312.42 71.12 0) (unit 1)
    (in_bom yes) (on_board yes) (dnp no) (fields_autoplaced)
    (property "Reference" "#PWR022" (at 321.31 73.66 0)
      (effects (font (size 1.27 1.27) (thickness 0.15)) (justify left bottom) hide)
    )
    (property "Value" "GND" (at 310.4098 76.2 0)
      (effects (font (size 1.27 1.27) (thickness 0.15)) (justify left bottom))
    )
    (property "Footprint" "" (at 321.31 78.74 0)
      (effects (font (size 1.27 1.27) (thickness 0.15)) (justify left bottom) hide)
    )
    (property "Datasheet" "" (at 321.31 83.82 0)
      (effects (font (size 1.27 1.27) (thickness 0.15)) (justify left bottom) hide)
    )
    (property "Author" "Antmicro" (at 321.31 78.74 0)
      (effects (font (size 1.27 1.27) (thickness 0.15)) (justify left bottom) hide)
    )
    (property "License" "Apache-2.0" (at 321.31 81.28 0)
      (effects (font (size 1.27 1.27) (thickness 0.15)) (justify left bottom) hide)
    )
    (pin "1")
    (instances
      (project "scalenode-cm4-baseboard"
        (path ""
          (reference "#PWR022") (unit 1)
        )
      )
    )
  )

  (symbol (lib_id "scalenode-cm4-baseboard:TP_0.75mm_SMD") (at 137.16 226.06 0) (unit 1)
    (in_bom yes) (on_board yes) (dnp no)
    (property "Reference" "TP1" (at 140.97 226.06 0)
      (effects (font (size 1.27 1.27) (thickness 0.15)) (justify left bottom))
    )
    (property "Value" "TP_0.75mm_SMD" (at 154.94 233.68 0)
      (effects (font (size 1.27 1.27) (thickness 0.15)) (justify left bottom) hide)
    )
    (property "Footprint" "scalenode-cm4-baseboard-footprints:TP_SMD_0.75mm" (at 154.94 236.22 0)
      (effects (font (size 1.27 1.27) (thickness 0.15)) (justify left bottom) hide)
    )
    (property "Datasheet" "" (at 154.94 238.76 0)
      (effects (font (size 1.27 1.27) (thickness 0.15)) (justify left bottom) hide)
    )
    (property "Author" "Antmicro" (at 154.94 246.38 0)
      (effects (font (size 1.27 1.27) (thickness 0.15)) (justify left bottom) hide)
    )
    (property "License" "Apache-2.0" (at 154.94 248.92 0)
      (effects (font (size 1.27 1.27) (thickness 0.15)) (justify left bottom) hide)
    )
    (property "MPN" "" (at 154.94 241.3 0)
      (effects (font (size 1.27 1.27) (thickness 0.15)) (justify left bottom) hide)
    )
    (property "Manufacturer" "" (at 154.94 243.84 0)
      (effects (font (size 1.27 1.27) (thickness 0.15)) (justify left bottom) hide)
    )
    (pin "1")
    (instances
      (project "scalenode-cm4-baseboard"
        (path ""
          (reference "TP1") (unit 1)
        )
      )
    )
  )

  (symbol (lib_id "scalenode-cm4-baseboard:R_24k9_0402") (at 96.52 220.98 0) (unit 1)
    (in_bom no) (on_board yes) (dnp yes)
    (property "Reference" "R36" (at 99.06 222.25 0)
      (effects (font (size 1.27 1.27) (thickness 0.15)) (justify right top))
    )
    (property "Value" "R_24k9_0402" (at 116.84 233.68 0)
      (effects (font (size 1.27 1.27) (thickness 0.15)) (justify left bottom) hide)
    )
    (property "Footprint" "scalenode-cm4-baseboard-footprints:R_0402_1005Metric" (at 116.84 236.22 0)
      (effects (font (size 1.27 1.27) (thickness 0.15)) (justify left bottom) hide)
    )
    (property "Datasheet" "https://www.bourns.com/docs/product-datasheets/cr.pdf" (at 116.84 238.76 0)
      (effects (font (size 1.27 1.27) (thickness 0.15)) (justify left bottom) hide)
    )
    (property "Manufacturer" "Bourns" (at 116.84 243.84 0)
      (effects (font (size 1.27 1.27) (thickness 0.15)) (justify left bottom) hide)
    )
    (property "MPN" "CR0402-FX-2492GLF" (at 116.84 241.3 0)
      (effects (font (size 1.27 1.27) (thickness 0.15)) (justify left bottom) hide)
    )
    (property "Val" "24k9" (at 100.33 222.25 0)
      (effects (font (size 1.27 1.27) (thickness 0.15)) (justify left top))
    )
    (property "DNP" "DNP" (at 99.06 220.98 0)
      (effects (font (size 1 1)))
    )
    (property "License" "Apache-2.0" (at 116.84 246.38 0)
      (effects (font (size 1.27 1.27) (thickness 0.15)) (justify left bottom) hide)
    )
    (property "Author" "Antmicro" (at 116.84 248.92 0)
      (effects (font (size 1.27 1.27) (thickness 0.15)) (justify left bottom) hide)
    )
    (property "Tolerance" "1%" (at 116.84 231.14 0)
      (effects (font (size 1.27 1.27)) (justify left bottom) hide)
    )
    (pin "1")
    (pin "2")
    (instances
      (project "scalenode-cm4-baseboard"
        (path ""
          (reference "R36") (unit 1)
        )
      )
    )
  )

  (symbol (lib_id "scalenode-cm4-baseboard:Earth") (at 173.99 134.62 0) (unit 1)
    (in_bom yes) (on_board yes) (dnp no) (fields_autoplaced)
    (property "Reference" "#PWR03" (at 173.99 140.97 0)
      (effects (font (size 1.27 1.27)) hide)
    )
    (property "Value" "Earth" (at 173.99 138.43 0)
      (effects (font (size 1.27 1.27)) hide)
    )
    (property "Footprint" "" (at 173.99 134.62 0)
      (effects (font (size 1.27 1.27)) hide)
    )
    (property "Datasheet" "" (at 173.99 134.62 0)
      (effects (font (size 1.27 1.27)) hide)
    )
    (pin "1")
    (instances
      (project "scalenode-cm4-baseboard"
        (path ""
          (reference "#PWR03") (unit 1)
        )
      )
    )
  )

  (symbol (lib_id "scalenode-cm4-baseboard:R_63R4_0402") (at 96.52 229.87 270) (unit 1)
    (in_bom no) (on_board yes) (dnp yes)
    (property "Reference" "R35" (at 97.79 232.41 90)
      (effects (font (size 1.27 1.27) (thickness 0.15)) (justify left bottom))
    )
    (property "Value" "R_63R4_0402" (at 83.82 250.19 0)
      (effects (font (size 1.27 1.27) (thickness 0.15)) (justify left bottom) hide)
    )
    (property "Footprint" "scalenode-cm4-baseboard-footprints:R_0402_1005Metric" (at 81.28 250.19 0)
      (effects (font (size 1.27 1.27) (thickness 0.15)) (justify left bottom) hide)
    )
    (property "Datasheet" "https://www.bourns.com/docs/product-datasheets/cr.pdf" (at 78.74 250.19 0)
      (effects (font (size 1.27 1.27) (thickness 0.15)) (justify left bottom) hide)
    )
    (property "Manufacturer" "Bourns" (at 73.66 250.19 0)
      (effects (font (size 1.27 1.27) (thickness 0.15)) (justify left bottom) hide)
    )
    (property "MPN" "CR0402-FX-63R4GLF" (at 76.2 250.19 0)
      (effects (font (size 1.27 1.27) (thickness 0.15)) (justify left bottom) hide)
    )
    (property "Val" "63R4" (at 97.79 234.95 90)
      (effects (font (size 1.27 1.27) (thickness 0.15)) (justify left bottom))
    )
    (property "DNP" "DNP" (at 96.52 232.41 0)
      (effects (font (size 1 1)))
    )
    (property "License" "Apache-2.0" (at 71.12 250.19 0)
      (effects (font (size 1.27 1.27) (thickness 0.15)) (justify left bottom) hide)
    )
    (property "Author" "Antmicro" (at 68.58 250.19 0)
      (effects (font (size 1.27 1.27) (thickness 0.15)) (justify left bottom) hide)
    )
    (property "Tolerance" "1%" (at 86.36 250.19 0)
      (effects (font (size 1.27 1.27)) (justify left bottom) hide)
    )
    (pin "1")
    (pin "2")
    (instances
      (project "scalenode-cm4-baseboard"
        (path ""
          (reference "R35") (unit 1)
        )
      )
    )
  )

  (symbol (lib_id "scalenode-cm4-baseboard:MB10S") (at 53.34 161.29 0) (unit 1)
    (in_bom yes) (on_board yes) (dnp no) (fields_autoplaced)
    (property "Reference" "D5" (at 58.98 175.26 0)
      (effects (font (size 1.27 1.27) (thickness 0.15)) (justify left bottom))
    )
    (property "Value" "MB10S" (at 81.28 166.37 0)
      (effects (font (size 1.27 1.27) (thickness 0.15)) (justify left bottom) hide)
    )
    (property "Footprint" "scalenode-cm4-baseboard-footprints:SOIC-4_W3.9mm" (at 81.28 168.91 0)
      (effects (font (size 1.27 1.27) (thickness 0.15)) (justify left bottom) hide)
    )
    (property "Datasheet" "http://www.farnell.com/datasheets/2895435.pdf" (at 81.28 171.45 0)
      (effects (font (size 1.27 1.27) (thickness 0.15)) (justify left bottom) hide)
    )
    (property "MPN" "MB10S" (at 58.98 177.8 0)
      (effects (font (size 1.27 1.27) (thickness 0.15)) (justify left bottom))
    )
    (property "Manufacturer" "Multicomp Pro" (at 81.28 176.53 0)
      (effects (font (size 1.27 1.27) (thickness 0.15)) (justify left bottom) hide)
    )
    (property "Author" "Antmicro" (at 81.28 179.07 0)
      (effects (font (size 1.27 1.27) (thickness 0.15)) (justify left bottom) hide)
    )
    (property "License" "Apache-2.0" (at 81.28 181.61 0)
      (effects (font (size 1.27 1.27) (thickness 0.15)) (justify left bottom) hide)
    )
    (pin "1")
    (pin "2")
    (pin "3")
    (pin "4")
    (instances
      (project "scalenode-cm4-baseboard"
        (path ""
          (reference "D5") (unit 1)
        )
      )
    )
  )

  (symbol (lib_id "scalenode-cm4-baseboard:TP_0.75mm_SMD") (at 137.16 231.14 0) (unit 1)
    (in_bom yes) (on_board yes) (dnp no)
    (property "Reference" "TP8" (at 140.97 231.14 0)
      (effects (font (size 1.27 1.27) (thickness 0.15)) (justify left bottom))
    )
    (property "Value" "TP_0.75mm_SMD" (at 154.94 238.76 0)
      (effects (font (size 1.27 1.27) (thickness 0.15)) (justify left bottom) hide)
    )
    (property "Footprint" "scalenode-cm4-baseboard-footprints:TP_SMD_0.75mm" (at 154.94 241.3 0)
      (effects (font (size 1.27 1.27) (thickness 0.15)) (justify left bottom) hide)
    )
    (property "Datasheet" "" (at 154.94 243.84 0)
      (effects (font (size 1.27 1.27) (thickness 0.15)) (justify left bottom) hide)
    )
    (property "Author" "Antmicro" (at 154.94 251.46 0)
      (effects (font (size 1.27 1.27) (thickness 0.15)) (justify left bottom) hide)
    )
    (property "License" "Apache-2.0" (at 154.94 254 0)
      (effects (font (size 1.27 1.27) (thickness 0.15)) (justify left bottom) hide)
    )
    (property "MPN" "" (at 154.94 246.38 0)
      (effects (font (size 1.27 1.27) (thickness 0.15)) (justify left bottom) hide)
    )
    (property "Manufacturer" "" (at 154.94 248.92 0)
      (effects (font (size 1.27 1.27) (thickness 0.15)) (justify left bottom) hide)
    )
    (pin "1")
    (instances
      (project "scalenode-cm4-baseboard"
        (path ""
          (reference "TP8") (unit 1)
        )
      )
    )
  )

  (symbol (lib_id "scalenode-cm4-baseboard:TP_1mm_SMD") (at 345.44 184.15 90) (unit 1)
    (in_bom yes) (on_board yes) (dnp no)
    (property "Reference" "TP5" (at 345.44 180.34 90)
      (effects (font (size 1.27 1.27) (thickness 0.15)) (justify top))
    )
    (property "Value" "TP_1mm_SMD" (at 353.06 168.91 0)
      (effects (font (size 1.27 1.27) (thickness 0.15)) (justify left bottom) hide)
    )
    (property "Footprint" "scalenode-cm4-baseboard-footprints:TP_SMD_1mm" (at 355.6 168.91 0)
      (effects (font (size 1.27 1.27) (thickness 0.15)) (justify left bottom) hide)
    )
    (property "Datasheet" "" (at 358.14 168.91 0)
      (effects (font (size 1.27 1.27) (thickness 0.15)) (justify left bottom) hide)
    )
    (property "Author" "Antmicro" (at 360.68 168.91 0)
      (effects (font (size 1.27 1.27) (thickness 0.15)) (justify left bottom) hide)
    )
    (property "License" "Apache-2.0" (at 363.22 168.91 0)
      (effects (font (size 1.27 1.27) (thickness 0.15)) (justify left bottom) hide)
    )
    (property "MPN" "" (at 345.44 184.15 0)
      (effects (font (size 1.27 1.27)) hide)
    )
    (property "Manufacturer" "" (at 345.44 184.15 0)
      (effects (font (size 1.27 1.27)) hide)
    )
    (pin "1")
    (instances
      (project "scalenode-cm4-baseboard"
        (path ""
          (reference "TP5") (unit 1)
        )
      )
    )
  )

  (symbol (lib_id "scalenode-cm4-baseboard:C_22u_100V_2220") (at 234.95 194.31 90) (unit 1)
    (in_bom yes) (on_board yes) (dnp no)
    (property "Reference" "C32" (at 234.95 193.04 90)
      (effects (font (size 1.27 1.27) (thickness 0.15)) (justify left bottom))
    )
    (property "Value" "C_22u_100V_2220" (at 245.11 173.99 0)
      (effects (font (size 1.27 1.27) (thickness 0.15)) (justify left bottom) hide)
    )
    (property "Footprint" "scalenode-cm4-baseboard-footprints:C_2220_5650Metric" (at 247.65 173.99 0)
      (effects (font (size 1.27 1.27) (thickness 0.15)) (justify left bottom) hide)
    )
    (property "Datasheet" "https://product.tdk.com/en/search/capacitor/ceramic/mlcc/info?part_no=C5750X7S2A226M280KB" (at 250.19 173.99 0)
      (effects (font (size 1.27 1.27) (thickness 0.15)) (justify left bottom) hide)
    )
    (property "Manufacturer" "TDK" (at 255.27 173.99 0)
      (effects (font (size 1.27 1.27) (thickness 0.15)) (justify left bottom) hide)
    )
    (property "MPN" "C5750X7S2A226M280KB" (at 252.73 173.99 0)
      (effects (font (size 1.27 1.27) (thickness 0.15)) (justify left bottom) hide)
    )
    (property "Val" "22u" (at 234.95 190.5 0)
      (effects (font (size 1.27 1.27) (thickness 0.15)) (justify left bottom))
    )
    (property "Author" "Antmicro" (at 260.35 173.99 0)
      (effects (font (size 1.27 1.27) (thickness 0.15)) (justify left bottom) hide)
    )
    (property "License" "Apache-2.0" (at 257.81 173.99 0)
      (effects (font (size 1.27 1.27) (thickness 0.15)) (justify left bottom) hide)
    )
    (property "Voltage" "100V" (at 262.89 173.99 0)
      (effects (font (size 1.27 1.27)) (justify left bottom) hide)
    )
    (property "Dielectric" "X7S" (at 265.43 173.99 0)
      (effects (font (size 1.27 1.27)) (justify left bottom) hide)
    )
    (pin "1")
    (pin "2")
    (instances
      (project "scalenode-cm4-baseboard"
        (path ""
          (reference "C32") (unit 1)
        )
      )
    )
  )

  (symbol (lib_id "scalenode-cm4-baseboard:SMAJ58A-13-F") (at 110.49 163.83 90) (unit 1)
    (in_bom yes) (on_board yes) (dnp no) (fields_autoplaced)
    (property "Reference" "D6" (at 106.68 158.1149 90)
      (effects (font (size 1.27 1.27) (thickness 0.15)) (justify left bottom))
    )
    (property "Value" "SMAJ58A-13-F" (at 106.68 160.6549 90)
      (effects (font (size 1.27 1.27) (thickness 0.15)) (justify left bottom))
    )
    (property "Footprint" "scalenode-cm4-baseboard-footprints:DO-214AC" (at 120.65 142.24 0)
      (effects (font (size 1.27 1.27) (thickness 0.15)) (justify left bottom) hide)
    )
    (property "Datasheet" "https://4donline.ihs.com/images/VipMasterIC/IC/DIOD/DIOD-S-A0001754755/DIOD-S-A0001754755-1.pdf?hkey=52A5661711E402568146F3353EA87419" (at 123.19 142.24 0)
      (effects (font (size 1.27 1.27) (thickness 0.15)) (justify left bottom) hide)
    )
    (property "MPN" "SMAJ58A-13-F" (at 125.73 142.24 0)
      (effects (font (size 1.27 1.27) (thickness 0.15)) (justify left bottom) hide)
    )
    (property "Manufacturer" "Diodes Incorporated" (at 128.27 142.24 0)
      (effects (font (size 1.27 1.27) (thickness 0.15)) (justify left bottom) hide)
    )
    (property "Author" "Antmicro" (at 130.81 142.24 0)
      (effects (font (size 1.27 1.27) (thickness 0.15)) (justify left bottom) hide)
    )
    (property "License" "Apache-2.0" (at 133.35 142.24 0)
      (effects (font (size 1.27 1.27) (thickness 0.15)) (justify left bottom) hide)
    )
    (pin "A")
    (pin "K")
    (instances
      (project "scalenode-cm4-baseboard"
        (path ""
          (reference "D6") (unit 1)
        )
      )
    )
  )

  (symbol (lib_id "scalenode-cm4-baseboard:R_63R4_0402") (at 85.09 229.87 270) (unit 1)
    (in_bom no) (on_board yes) (dnp yes)
    (property "Reference" "R20" (at 86.36 232.41 90)
      (effects (font (size 1.27 1.27) (thickness 0.15)) (justify left bottom))
    )
    (property "Value" "R_63R4_0402" (at 72.39 250.19 0)
      (effects (font (size 1.27 1.27) (thickness 0.15)) (justify left bottom) hide)
    )
    (property "Footprint" "scalenode-cm4-baseboard-footprints:R_0402_1005Metric" (at 69.85 250.19 0)
      (effects (font (size 1.27 1.27) (thickness 0.15)) (justify left bottom) hide)
    )
    (property "Datasheet" "https://www.bourns.com/docs/product-datasheets/cr.pdf" (at 67.31 250.19 0)
      (effects (font (size 1.27 1.27) (thickness 0.15)) (justify left bottom) hide)
    )
    (property "Manufacturer" "Bourns" (at 62.23 250.19 0)
      (effects (font (size 1.27 1.27) (thickness 0.15)) (justify left bottom) hide)
    )
    (property "MPN" "CR0402-FX-63R4GLF" (at 64.77 250.19 0)
      (effects (font (size 1.27 1.27) (thickness 0.15)) (justify left bottom) hide)
    )
    (property "Val" "63R4" (at 86.36 234.95 90)
      (effects (font (size 1.27 1.27) (thickness 0.15)) (justify left bottom))
    )
    (property "DNP" "DNP" (at 85.09 232.41 0)
      (effects (font (size 1 1)))
    )
    (property "License" "Apache-2.0" (at 59.69 250.19 0)
      (effects (font (size 1.27 1.27) (thickness 0.15)) (justify left bottom) hide)
    )
    (property "Author" "Antmicro" (at 57.15 250.19 0)
      (effects (font (size 1.27 1.27) (thickness 0.15)) (justify left bottom) hide)
    )
    (property "Tolerance" "1%" (at 74.93 250.19 0)
      (effects (font (size 1.27 1.27)) (justify left bottom) hide)
    )
    (pin "1")
    (pin "2")
    (instances
      (project "scalenode-cm4-baseboard"
        (path ""
          (reference "R20") (unit 1)
        )
      )
    )
  )

  (symbol (lib_id "scalenode-cm4-baseboard:R_63R4_0402") (at 127 168.91 0) (unit 1)
    (in_bom yes) (on_board yes) (dnp no) (fields_autoplaced)
    (property "Reference" "R23" (at 127.0157 172.72 0)
      (effects (font (size 1.27 1.27) (thickness 0.15)) (justify left bottom))
    )
    (property "Value" "R_63R4_0402" (at 147.32 181.61 0)
      (effects (font (size 1.27 1.27) (thickness 0.15)) (justify left bottom) hide)
    )
    (property "Footprint" "scalenode-cm4-baseboard-footprints:R_0402_1005Metric" (at 147.32 184.15 0)
      (effects (font (size 1.27 1.27) (thickness 0.15)) (justify left bottom) hide)
    )
    (property "Datasheet" "https://www.bourns.com/docs/product-datasheets/cr.pdf" (at 147.32 186.69 0)
      (effects (font (size 1.27 1.27) (thickness 0.15)) (justify left bottom) hide)
    )
    (property "Manufacturer" "Bourns" (at 147.32 191.77 0)
      (effects (font (size 1.27 1.27) (thickness 0.15)) (justify left bottom) hide)
    )
    (property "MPN" "CR0402-FX-63R4GLF" (at 147.32 189.23 0)
      (effects (font (size 1.27 1.27) (thickness 0.15)) (justify left bottom) hide)
    )
    (property "Val" "63R4" (at 127.0157 175.26 0)
      (effects (font (size 1.27 1.27) (thickness 0.15)) (justify left bottom))
    )
    (property "License" "Apache-2.0" (at 147.32 194.31 0)
      (effects (font (size 1.27 1.27) (thickness 0.15)) (justify left bottom) hide)
    )
    (property "Author" "Antmicro" (at 147.32 196.85 0)
      (effects (font (size 1.27 1.27) (thickness 0.15)) (justify left bottom) hide)
    )
    (property "Tolerance" "1%" (at 147.32 179.07 0)
      (effects (font (size 1.27 1.27)) (justify left bottom) hide)
    )
    (pin "1")
    (pin "2")
    (instances
      (project "scalenode-cm4-baseboard"
        (path ""
          (reference "R23") (unit 1)
        )
      )
    )
  )

  (symbol (lib_id "scalenode-cm4-baseboard:R_10k_0402") (at 149.86 215.9 90) (unit 1)
    (in_bom no) (on_board yes) (dnp yes)
    (property "Reference" "R40" (at 154.94 210.82 90)
      (effects (font (size 1.27 1.27) (thickness 0.15)) (justify left bottom))
    )
    (property "Value" "R_10k_0402" (at 162.56 195.58 0)
      (effects (font (size 1.27 1.27) (thickness 0.15)) (justify left bottom) hide)
    )
    (property "Footprint" "scalenode-cm4-baseboard-footprints:R_0402_1005Metric" (at 165.1 195.58 0)
      (effects (font (size 1.27 1.27) (thickness 0.15)) (justify left bottom) hide)
    )
    (property "Datasheet" "https://www.bourns.com/docs/product-datasheets/cr.pdf" (at 167.64 195.58 0)
      (effects (font (size 1.27 1.27) (thickness 0.15)) (justify left bottom) hide)
    )
    (property "Manufacturer" "Bourns" (at 172.72 195.58 0)
      (effects (font (size 1.27 1.27) (thickness 0.15)) (justify left bottom) hide)
    )
    (property "MPN" "CR0402-FX-1002GLF" (at 170.18 195.58 0)
      (effects (font (size 1.27 1.27) (thickness 0.15)) (justify left bottom) hide)
    )
    (property "Val" "10k" (at 154.94 213.36 90)
      (effects (font (size 1.27 1.27) (thickness 0.15)) (justify left bottom))
    )
    (property "DNP" "DNP" (at 149.86 213.36 0)
      (effects (font (size 1 1)))
    )
    (property "License" "Apache-2.0" (at 175.26 195.58 0)
      (effects (font (size 1.27 1.27) (thickness 0.15)) (justify left bottom) hide)
    )
    (property "Author" "Antmicro" (at 177.8 195.58 0)
      (effects (font (size 1.27 1.27) (thickness 0.15)) (justify left bottom) hide)
    )
    (property "Tolerance" "1%" (at 160.02 195.58 0)
      (effects (font (size 1.27 1.27)) (justify left bottom) hide)
    )
    (pin "1")
    (pin "2")
    (instances
      (project "scalenode-cm4-baseboard"
        (path ""
          (reference "R40") (unit 1)
        )
      )
    )
  )

  (symbol (lib_id "scalenode-cm4-baseboard:C_10n_0402") (at 163.83 107.95 90) (unit 1)
    (in_bom yes) (on_board yes) (dnp no)
    (property "Reference" "C27" (at 163.83 102.87 90)
      (effects (font (size 1.27 1.27) (thickness 0.15)) (justify left bottom))
    )
    (property "Value" "C_10n_0402" (at 173.99 87.63 0)
      (effects (font (size 1.27 1.27) (thickness 0.15)) (justify left bottom) hide)
    )
    (property "Footprint" "scalenode-cm4-baseboard-footprints:C_0402_1005Metric" (at 176.53 87.63 0)
      (effects (font (size 1.27 1.27) (thickness 0.15)) (justify left bottom) hide)
    )
    (property "Datasheet" "https://www.murata.com/products/productdetail?partno=GRM155R71H103KA88%23" (at 179.07 87.63 0)
      (effects (font (size 1.27 1.27) (thickness 0.15)) (justify left bottom) hide)
    )
    (property "Manufacturer" "Murata" (at 184.15 87.63 0)
      (effects (font (size 1.27 1.27) (thickness 0.15)) (justify left bottom) hide)
    )
    (property "MPN" "GRM155R71H103KA88D" (at 181.61 87.63 0)
      (effects (font (size 1.27 1.27) (thickness 0.15)) (justify left bottom) hide)
    )
    (property "Val" "10n" (at 163.83 106.68 90)
      (effects (font (size 1.27 1.27) (thickness 0.15)) (justify left bottom))
    )
    (property "License" "Apache-2.0" (at 186.69 87.63 0)
      (effects (font (size 1.27 1.27) (thickness 0.15)) (justify left bottom) hide)
    )
    (property "Author" "Antmicro" (at 189.23 87.63 0)
      (effects (font (size 1.27 1.27) (thickness 0.15)) (justify left bottom) hide)
    )
    (property "Voltage" "50V" (at 191.77 87.63 0)
      (effects (font (size 1.27 1.27)) (justify left bottom) hide)
    )
    (property "Dielectric" "X7R" (at 194.31 87.63 0)
      (effects (font (size 1.27 1.27)) (justify left bottom) hide)
    )
    (pin "1")
    (pin "2")
    (instances
      (project "scalenode-cm4-baseboard"
        (path ""
          (reference "C27") (unit 1)
        )
      )
    )
  )

  (symbol (lib_id "scalenode-cm4-baseboard:C_10n_0402") (at 170.18 107.95 90) (unit 1)
    (in_bom yes) (on_board yes) (dnp no)
    (property "Reference" "C30" (at 170.18 102.87 90)
      (effects (font (size 1.27 1.27) (thickness 0.15)) (justify left bottom))
    )
    (property "Value" "C_10n_0402" (at 180.34 87.63 0)
      (effects (font (size 1.27 1.27) (thickness 0.15)) (justify left bottom) hide)
    )
    (property "Footprint" "scalenode-cm4-baseboard-footprints:C_0402_1005Metric" (at 182.88 87.63 0)
      (effects (font (size 1.27 1.27) (thickness 0.15)) (justify left bottom) hide)
    )
    (property "Datasheet" "https://www.murata.com/products/productdetail?partno=GRM155R71H103KA88%23" (at 185.42 87.63 0)
      (effects (font (size 1.27 1.27) (thickness 0.15)) (justify left bottom) hide)
    )
    (property "Manufacturer" "Murata" (at 190.5 87.63 0)
      (effects (font (size 1.27 1.27) (thickness 0.15)) (justify left bottom) hide)
    )
    (property "MPN" "GRM155R71H103KA88D" (at 187.96 87.63 0)
      (effects (font (size 1.27 1.27) (thickness 0.15)) (justify left bottom) hide)
    )
    (property "Val" "10n" (at 170.18 106.68 90)
      (effects (font (size 1.27 1.27) (thickness 0.15)) (justify left bottom))
    )
    (property "License" "Apache-2.0" (at 193.04 87.63 0)
      (effects (font (size 1.27 1.27) (thickness 0.15)) (justify left bottom) hide)
    )
    (property "Author" "Antmicro" (at 195.58 87.63 0)
      (effects (font (size 1.27 1.27) (thickness 0.15)) (justify left bottom) hide)
    )
    (property "Voltage" "50V" (at 198.12 87.63 0)
      (effects (font (size 1.27 1.27)) (justify left bottom) hide)
    )
    (property "Dielectric" "X7R" (at 200.66 87.63 0)
      (effects (font (size 1.27 1.27)) (justify left bottom) hide)
    )
    (pin "1")
    (pin "2")
    (instances
      (project "scalenode-cm4-baseboard"
        (path ""
          (reference "C30") (unit 1)
        )
      )
    )
  )

  (symbol (lib_id "scalenode-cm4-baseboard:GND") (at 312.42 233.68 0) (unit 1)
    (in_bom yes) (on_board yes) (dnp no) (fields_autoplaced)
    (property "Reference" "#PWR0117" (at 321.31 236.22 0)
      (effects (font (size 1.27 1.27) (thickness 0.15)) (justify left bottom) hide)
    )
    (property "Value" "GND" (at 310.4098 238.76 0)
      (effects (font (size 1.27 1.27) (thickness 0.15)) (justify left bottom))
    )
    (property "Footprint" "" (at 321.31 241.3 0)
      (effects (font (size 1.27 1.27) (thickness 0.15)) (justify left bottom) hide)
    )
    (property "Datasheet" "" (at 321.31 246.38 0)
      (effects (font (size 1.27 1.27) (thickness 0.15)) (justify left bottom) hide)
    )
    (property "Author" "Antmicro" (at 321.31 241.3 0)
      (effects (font (size 1.27 1.27) (thickness 0.15)) (justify left bottom) hide)
    )
    (property "License" "Apache-2.0" (at 321.31 243.84 0)
      (effects (font (size 1.27 1.27) (thickness 0.15)) (justify left bottom) hide)
    )
    (pin "1")
    (instances
      (project "scalenode-cm4-baseboard"
        (path ""
          (reference "#PWR0117") (unit 1)
        )
      )
    )
  )

  (symbol (lib_id "scalenode-cm4-baseboard:PDQE30-Q48-S5-D") (at 279.4 185.42 0) (unit 1)
    (in_bom yes) (on_board yes) (dnp no) (fields_autoplaced)
    (property "Reference" "U7" (at 279.6879 177.8 0)
      (effects (font (size 1.27 1.27) (thickness 0.15)) (justify left bottom))
    )
    (property "Value" "PDQE30-Q48-S5-D" (at 314.96 193.04 0)
      (effects (font (size 1.27 1.27) (thickness 0.15)) (justify left bottom) hide)
    )
    (property "Footprint" "scalenode-cm4-baseboard-footprints:CONV_PDQE30-Q48-S5-D" (at 314.96 195.58 0)
      (effects (font (size 1.27 1.27) (thickness 0.15)) (justify left bottom) hide)
    )
    (property "Datasheet" "https://www.cui.com/product/resource/pdqe30-d.pdf" (at 314.96 198.12 0)
      (effects (font (size 1.27 1.27) (thickness 0.15)) (justify left bottom) hide)
    )
    (property "MPN" "PDQE30-Q48-S5-D" (at 279.6879 180.34 0)
      (effects (font (size 1.27 1.27) (thickness 0.15)) (justify left bottom))
    )
    (property "Manufacturer" "CUI Inc" (at 314.96 200.66 0)
      (effects (font (size 1.27 1.27) (thickness 0.15)) (justify left bottom) hide)
    )
    (property "Author" "Antmicro" (at 314.96 203.2 0)
      (effects (font (size 1.27 1.27) (thickness 0.15)) (justify left bottom) hide)
    )
    (property "License" "Apache-2.0" (at 314.96 205.74 0)
      (effects (font (size 1.27 1.27) (thickness 0.15)) (justify left bottom) hide)
    )
    (pin "1")
    (pin "2")
    (pin "3")
    (pin "4")
    (pin "5")
    (pin "6")
    (instances
      (project "scalenode-cm4-baseboard"
        (path ""
          (reference "U7") (unit 1)
        )
      )
    )
  )

  (symbol (lib_id "scalenode-cm4-baseboard:GNDD") (at 266.7 233.68 0) (unit 1)
    (in_bom yes) (on_board yes) (dnp no) (fields_autoplaced)
    (property "Reference" "#PWR0116" (at 281.94 236.22 0)
      (effects (font (size 1.27 1.27) (thickness 0.15)) (justify left bottom) hide)
    )
    (property "Value" "GNDD" (at 264.0548 238.76 0)
      (effects (font (size 1.27 1.27) (thickness 0.15)) (justify left bottom))
    )
    (property "Footprint" "" (at 281.94 243.84 0)
      (effects (font (size 1.27 1.27) (thickness 0.15)) (justify left bottom) hide)
    )
    (property "Datasheet" "" (at 281.94 246.38 0)
      (effects (font (size 1.27 1.27) (thickness 0.15)) (justify left bottom) hide)
    )
    (property "Author" "Antmicro" (at 281.94 241.3 0)
      (effects (font (size 1.27 1.27) (thickness 0.15)) (justify left bottom) hide)
    )
    (property "License" "Apache-2.0" (at 281.94 243.84 0)
      (effects (font (size 1.27 1.27) (thickness 0.15)) (justify left bottom) hide)
    )
    (pin "1")
    (instances
      (project "scalenode-cm4-baseboard"
        (path ""
          (reference "#PWR0116") (unit 1)
        )
      )
    )
  )
)
